FILE_TYPE = MACRO_DRAWING;
SET COLOR_WIRE YELLOW;
SET COLOR_PROP ORANGE;
SET COLOR_DOT WHITE;
SET COLOR_ARC YELLOW;
SET COLOR_BODY GREEN;
SET COLOR_NOTE PURPLE;
SET PROP_DISPLAY VALUE;
SET PAGE_NUMBER P275;
FORCEADD TAP..6
(-6375 4175);
FORCEPROP 3 LASTPIN (-6325 4175) SIG_NAME P5E_CPU0_G3_TX_DN<15>
J 0
(-6315 4185);
DISPLAY 0.659574 (-6315 4185);
PAINT MONO (-6315 4185);
DISPLAY INVISIBLE (-6315 4185);
FORCEPROP 1 LASTPIN (-6325 4175) BN 15
J 0
(-6377 4183);
DISPLAY 0.680851 (-6377 4183);
PAINT MONO (-6377 4183);
FORCEPROP 2 LAST CDS_LIB standard
J 0
(-6375 4175);
DISPLAY INVISIBLE (-6375 4175);
FORCEPROP 1 LAST PATH I1
J 0
(-6377 4175);
DISPLAY 0.872340 (-6377 4175);
PAINT GREEN (-6377 4175);
DISPLAY INVISIBLE (-6377 4175);
FORCEPROP 1 LAST HDL_TAP TRUE
J 0
(-6050 4050);
DISPLAY 0.574468 (-6050 4050);
PAINT GREEN (-6050 4050);
DISPLAY INVISIBLE (-6050 4050);
FORCEPROP 1 LAST BODY_TYPE PLUMBING
J 0
(-6375 4125);
DISPLAY 0.574468 (-6375 4125);
PAINT GREEN (-6375 4125);
DISPLAY INVISIBLE (-6375 4125);
FORCEADD TAP..6
(-6375 4475);
FORCEPROP 3 LASTPIN (-6325 4475) SIG_NAME P5E_CPU0_G3_TX_DN<12>
J 0
(-6315 4485);
DISPLAY 0.659574 (-6315 4485);
PAINT MONO (-6315 4485);
DISPLAY INVISIBLE (-6315 4485);
FORCEPROP 1 LASTPIN (-6325 4475) BN 12
J 0
(-6377 4483);
DISPLAY 0.680851 (-6377 4483);
PAINT MONO (-6377 4483);
FORCEPROP 2 LAST CDS_LIB standard
J 0
(-6375 4475);
DISPLAY INVISIBLE (-6375 4475);
FORCEPROP 1 LAST PATH I10
J 0
(-6377 4475);
DISPLAY 0.872340 (-6377 4475);
PAINT GREEN (-6377 4475);
DISPLAY INVISIBLE (-6377 4475);
FORCEPROP 1 LAST HDL_TAP TRUE
J 0
(-6050 4350);
DISPLAY 0.574468 (-6050 4350);
PAINT GREEN (-6050 4350);
DISPLAY INVISIBLE (-6050 4350);
FORCEPROP 1 LAST BODY_TYPE PLUMBING
J 0
(-6375 4425);
DISPLAY 0.574468 (-6375 4425);
PAINT GREEN (-6375 4425);
DISPLAY INVISIBLE (-6375 4425);
FORCEADD OFFPAGE..2
(-3375 5950);
FORCEPROP 2 LAST CDS_LIB standard
J 0
(-3375 5950);
DISPLAY INVISIBLE (-3375 5950);
FORCEPROP 2 LAST PATH I100
J 0
(-3200 6025);
DISPLAY 0.680851 (-3200 6025);
DISPLAY INVISIBLE (-3200 6025);
FORCEPROP 1 LAST COMMENT_BODY TRUE
J 0
(-3420 5855);
DISPLAY 0.872340 (-3420 5855);
PAINT GREEN (-3420 5855);
DISPLAY INVISIBLE (-3420 5855);
FORCEPROP 1 LAST OFFPAGE TRUE
J 0
(-3050 5825);
DISPLAY 0.872340 (-3050 5825);
PAINT GREEN (-3050 5825);
DISPLAY INVISIBLE (-3050 5825);
FORCEADD Q_CAP_DIFFBUS..2
(-5500 5725);
FORCEPROP 1 LAST LOCATION C461
J 0
(-5350 5725);
DISPLAY 0.723404 (-5350 5725);
PAINT GREEN (-5350 5725);
FORCEPROP 0 LAST $SEC 1
J 0
(-5700 5875);
DISPLAY 0.680851 (-5700 5875);
PAINT MONO (-5700 5875);
DISPLAY INVISIBLE (-5700 5875);
FORCEPROP 0 LAST CDS_SEC 1
J 0
(-5700 5875);
DISPLAY 0.680851 (-5700 5875);
DISPLAY INVISIBLE (-5700 5875);
FORCEPROP 0 LASTPIN (-5575 5725) $PN 1
J 2
(-5585 5735);
DISPLAY 0.680851 (-5585 5735);
PAINT MONO (-5585 5735);
FORCEPROP 0 LASTPIN (-5425 5725) $PN 2
J 0
(-5415 5735);
DISPLAY 0.680851 (-5415 5735);
PAINT MONO (-5415 5735);
FORCEPROP 2 LAST PACK_TYPE C0201
J 0
(-5725 5775);
DISPLAY 0.680851 (-5725 5775);
FORCEPROP 2 LAST VALUE DIFF BUS_0.22UF
J 0
(-6075 5725);
DISPLAY 0.680851 (-6075 5725);
FORCEPROP 1 LAST MATERIAL X6S
J 0
(-5550 5775);
DISPLAY 0.723404 (-5550 5775);
PAINT GREEN (-5550 5775);
FORCEPROP 2 LAST TOLERANCE 20%
J 0
(-5425 5775);
DISPLAY 0.680851 (-5425 5775);
FORCEPROP 1 LAST PART_NUMBER SP_CH4221MEE01
J 0
(-5700 5825);
DISPLAY 0.723404 (-5700 5825);
PAINT GREEN (-5700 5825);
FORCEPROP 2 LAST VOLTAGE 6.3V
J 0
(-5300 5775);
DISPLAY 0.680851 (-5300 5775);
FORCEPROP 1 LAST CDS_LMAN_SYM_OUTLINE -25,50,25,-50
J 0
(-5500 5725);
DISPLAY 0.468085 (-5500 5725);
PAINT GREEN (-5500 5725);
DISPLAY INVISIBLE (-5500 5725);
FORCEPROP 1 LAST PATH I101
J 0
(-5500 5725);
DISPLAY 0.723404 (-5500 5725);
DISPLAY INVISIBLE (-5500 5725);
FORCEPROP 1 LAST PIN_NAMES_ROTATE True
J 0
(-5500 5725);
DISPLAY 0.489362 (-5500 5725);
PAINT GREEN (-5500 5725);
DISPLAY INVISIBLE (-5500 5725);
FORCEPROP 2 LAST CDS_LIB pure_quanta
J 0
(-5500 5725);
DISPLAY INVISIBLE (-5500 5725);
FORCEADD Q_CAP_DIFFBUS..2
R 2
(-5500 5675);
FORCEPROP 1 LAST LOCATION C462
J 2
(-5250 5675);
DISPLAY 0.723404 (-5250 5675);
PAINT GREEN (-5250 5675);
FORCEPROP 2 LAST SEC 1
J 2
(-5600 5725);
DISPLAY 0.680851 (-5600 5725);
PAINT MONO (-5600 5725);
DISPLAY INVISIBLE (-5600 5725);
FORCEPROP 2 LASTPIN (-5425 5675) $PN 1
J 0
(-5415 5685);
DISPLAY 0.680851 (-5415 5685);
PAINT MONO (-5415 5685);
FORCEPROP 2 LASTPIN (-5575 5675) $PN 2
J 2
(-5585 5685);
DISPLAY 0.680851 (-5585 5685);
PAINT MONO (-5585 5685);
FORCEPROP 2 LAST VALUE DIFF BUS_0.22UF
J 2
(-5625 5675);
DISPLAY 0.553191 (-5625 5675);
FORCEPROP 0 LAST VOLTAGE 6.3V
J 2
(-5575 5850);
DISPLAY 0.680851 (-5575 5850);
DISPLAY INVISIBLE (-5575 5850);
FORCEPROP 0 LAST TOLERANCE 20%
J 2
(-5575 5800);
DISPLAY 0.680851 (-5575 5800);
DISPLAY INVISIBLE (-5575 5800);
FORCEPROP 1 LAST PART_NUMBER SP_CH4221MEE01
J 2
(-5475 5750);
DISPLAY 0.723404 (-5475 5750);
PAINT GREEN (-5475 5750);
DISPLAY INVISIBLE (-5475 5750);
FORCEPROP 1 LAST MATERIAL X6S
J 2
(-5350 5725);
DISPLAY 0.723404 (-5350 5725);
PAINT GREEN (-5350 5725);
DISPLAY INVISIBLE (-5350 5725);
FORCEPROP 2 LAST CDS_LIB pure_quanta
J 2
(-5500 5675);
DISPLAY INVISIBLE (-5500 5675);
FORCEPROP 1 LAST PATH I102
J 2
(-5500 5675);
DISPLAY 0.723404 (-5500 5675);
DISPLAY INVISIBLE (-5500 5675);
FORCEPROP 1 LAST CDS_LMAN_SYM_OUTLINE -25,50,25,-50
J 2
(-5500 5675);
DISPLAY 0.468085 (-5500 5675);
PAINT GREEN (-5500 5675);
DISPLAY INVISIBLE (-5500 5675);
FORCEPROP 1 LAST PIN_NAMES_ROTATE True
J 2
(-5500 5675);
DISPLAY 0.489362 (-5500 5675);
PAINT GREEN (-5500 5675);
DISPLAY INVISIBLE (-5500 5675);
FORCEPROP 2 LAST SEC_TYPE C0201
J 2
(-5600 5725);
DISPLAY 0.680851 (-5600 5725);
DISPLAY INVISIBLE (-5600 5725);
FORCEPROP 0 LAST PACK_TYPE C0201
J 2
(-5650 5675);
DISPLAY 0.680851 (-5650 5675);
DISPLAY INVISIBLE (-5650 5675);
FORCEADD Q_CAP_DIFFBUS..2
R 2
(-5500 5625);
FORCEPROP 1 LAST LOCATION C463
J 2
(-5250 5625);
DISPLAY 0.723404 (-5250 5625);
PAINT GREEN (-5250 5625);
FORCEPROP 0 LAST $SEC 1
J 0
(-5250 5675);
DISPLAY 0.680851 (-5250 5675);
PAINT MONO (-5250 5675);
DISPLAY INVISIBLE (-5250 5675);
FORCEPROP 0 LAST CDS_SEC 1
J 0
(-5250 5675);
DISPLAY 0.680851 (-5250 5675);
DISPLAY INVISIBLE (-5250 5675);
FORCEPROP 0 LASTPIN (-5425 5625) $PN 1
J 0
(-5415 5635);
DISPLAY 0.680851 (-5415 5635);
PAINT MONO (-5415 5635);
FORCEPROP 0 LASTPIN (-5575 5625) $PN 2
J 2
(-5585 5635);
DISPLAY 0.680851 (-5585 5635);
PAINT MONO (-5585 5635);
FORCEPROP 2 LAST VALUE DIFF BUS_0.22UF
J 2
(-5625 5625);
DISPLAY 0.553191 (-5625 5625);
FORCEPROP 0 LAST VOLTAGE 6.3V
J 2
(-5575 5800);
DISPLAY 0.680851 (-5575 5800);
DISPLAY INVISIBLE (-5575 5800);
FORCEPROP 0 LAST TOLERANCE 20%
J 2
(-5575 5750);
DISPLAY 0.680851 (-5575 5750);
DISPLAY INVISIBLE (-5575 5750);
FORCEPROP 1 LAST PART_NUMBER SP_CH4221MEE01
J 2
(-5475 5700);
DISPLAY 0.723404 (-5475 5700);
PAINT GREEN (-5475 5700);
DISPLAY INVISIBLE (-5475 5700);
FORCEPROP 1 LAST MATERIAL X6S
J 2
(-5350 5675);
DISPLAY 0.723404 (-5350 5675);
PAINT GREEN (-5350 5675);
DISPLAY INVISIBLE (-5350 5675);
FORCEPROP 1 LAST PIN_NAMES_ROTATE True
J 2
(-5500 5625);
DISPLAY 0.489362 (-5500 5625);
PAINT GREEN (-5500 5625);
DISPLAY INVISIBLE (-5500 5625);
FORCEPROP 0 LAST PACK_TYPE C0201
J 2
(-5650 5625);
DISPLAY 0.680851 (-5650 5625);
DISPLAY INVISIBLE (-5650 5625);
FORCEPROP 1 LAST CDS_LMAN_SYM_OUTLINE -25,50,25,-50
J 2
(-5500 5625);
DISPLAY 0.468085 (-5500 5625);
PAINT GREEN (-5500 5625);
DISPLAY INVISIBLE (-5500 5625);
FORCEPROP 1 LAST PATH I103
J 2
(-5500 5625);
DISPLAY 0.723404 (-5500 5625);
DISPLAY INVISIBLE (-5500 5625);
FORCEPROP 2 LAST CDS_LIB pure_quanta
J 0
(-5500 5625);
DISPLAY INVISIBLE (-5500 5625);
FORCEADD Q_CAP_DIFFBUS..2
R 2
(-5500 5525);
FORCEPROP 1 LAST LOCATION C465
J 2
(-5250 5525);
DISPLAY 0.723404 (-5250 5525);
PAINT GREEN (-5250 5525);
FORCEPROP 0 LAST $SEC 1
J 0
(-5250 5575);
DISPLAY 0.680851 (-5250 5575);
PAINT MONO (-5250 5575);
DISPLAY INVISIBLE (-5250 5575);
FORCEPROP 0 LAST CDS_SEC 1
J 0
(-5250 5575);
DISPLAY 0.680851 (-5250 5575);
DISPLAY INVISIBLE (-5250 5575);
FORCEPROP 0 LASTPIN (-5425 5525) $PN 1
J 0
(-5415 5535);
DISPLAY 0.680851 (-5415 5535);
PAINT MONO (-5415 5535);
FORCEPROP 0 LASTPIN (-5575 5525) $PN 2
J 2
(-5585 5535);
DISPLAY 0.680851 (-5585 5535);
PAINT MONO (-5585 5535);
FORCEPROP 2 LAST VALUE DIFF BUS_0.22UF
J 2
(-5625 5525);
DISPLAY 0.553191 (-5625 5525);
FORCEPROP 0 LAST PACK_TYPE C0201
J 2
(-5650 5525);
DISPLAY 0.680851 (-5650 5525);
DISPLAY INVISIBLE (-5650 5525);
FORCEPROP 1 LAST PIN_NAMES_ROTATE True
J 2
(-5500 5525);
DISPLAY 0.489362 (-5500 5525);
PAINT GREEN (-5500 5525);
DISPLAY INVISIBLE (-5500 5525);
FORCEPROP 1 LAST MATERIAL X6S
J 2
(-5350 5575);
DISPLAY 0.723404 (-5350 5575);
PAINT GREEN (-5350 5575);
DISPLAY INVISIBLE (-5350 5575);
FORCEPROP 1 LAST PART_NUMBER SP_CH4221MEE01
J 2
(-5475 5600);
DISPLAY 0.723404 (-5475 5600);
PAINT GREEN (-5475 5600);
DISPLAY INVISIBLE (-5475 5600);
FORCEPROP 0 LAST TOLERANCE 20%
J 2
(-5575 5650);
DISPLAY 0.680851 (-5575 5650);
DISPLAY INVISIBLE (-5575 5650);
FORCEPROP 0 LAST VOLTAGE 6.3V
J 2
(-5575 5700);
DISPLAY 0.680851 (-5575 5700);
DISPLAY INVISIBLE (-5575 5700);
FORCEPROP 1 LAST CDS_LMAN_SYM_OUTLINE -25,50,25,-50
J 2
(-5500 5525);
DISPLAY 0.468085 (-5500 5525);
PAINT GREEN (-5500 5525);
DISPLAY INVISIBLE (-5500 5525);
FORCEPROP 1 LAST PATH I104
J 2
(-5500 5525);
DISPLAY 0.723404 (-5500 5525);
DISPLAY INVISIBLE (-5500 5525);
FORCEPROP 2 LAST CDS_LIB pure_quanta
J 0
(-5500 5525);
DISPLAY INVISIBLE (-5500 5525);
FORCEADD Q_CAP_DIFFBUS..2
R 2
(-5500 5575);
FORCEPROP 1 LAST LOCATION C464
J 2
(-5250 5575);
DISPLAY 0.723404 (-5250 5575);
PAINT GREEN (-5250 5575);
FORCEPROP 0 LAST $SEC 1
J 0
(-5250 5625);
DISPLAY 0.680851 (-5250 5625);
PAINT MONO (-5250 5625);
DISPLAY INVISIBLE (-5250 5625);
FORCEPROP 0 LAST CDS_SEC 1
J 0
(-5250 5625);
DISPLAY 0.680851 (-5250 5625);
DISPLAY INVISIBLE (-5250 5625);
FORCEPROP 0 LASTPIN (-5425 5575) $PN 1
J 0
(-5415 5585);
DISPLAY 0.680851 (-5415 5585);
PAINT MONO (-5415 5585);
FORCEPROP 0 LASTPIN (-5575 5575) $PN 2
J 2
(-5585 5585);
DISPLAY 0.680851 (-5585 5585);
PAINT MONO (-5585 5585);
FORCEPROP 2 LAST VALUE DIFF BUS_0.22UF
J 2
(-5625 5575);
DISPLAY 0.553191 (-5625 5575);
FORCEPROP 0 LAST VOLTAGE 6.3V
J 2
(-5575 5750);
DISPLAY 0.680851 (-5575 5750);
DISPLAY INVISIBLE (-5575 5750);
FORCEPROP 0 LAST TOLERANCE 20%
J 2
(-5575 5700);
DISPLAY 0.680851 (-5575 5700);
DISPLAY INVISIBLE (-5575 5700);
FORCEPROP 1 LAST PART_NUMBER SP_CH4221MEE01
J 2
(-5475 5650);
DISPLAY 0.723404 (-5475 5650);
PAINT GREEN (-5475 5650);
DISPLAY INVISIBLE (-5475 5650);
FORCEPROP 1 LAST MATERIAL X6S
J 2
(-5350 5625);
DISPLAY 0.723404 (-5350 5625);
PAINT GREEN (-5350 5625);
DISPLAY INVISIBLE (-5350 5625);
FORCEPROP 1 LAST PIN_NAMES_ROTATE True
J 2
(-5500 5575);
DISPLAY 0.489362 (-5500 5575);
PAINT GREEN (-5500 5575);
DISPLAY INVISIBLE (-5500 5575);
FORCEPROP 0 LAST PACK_TYPE C0201
J 2
(-5650 5575);
DISPLAY 0.680851 (-5650 5575);
DISPLAY INVISIBLE (-5650 5575);
FORCEPROP 1 LAST CDS_LMAN_SYM_OUTLINE -25,50,25,-50
J 2
(-5500 5575);
DISPLAY 0.468085 (-5500 5575);
PAINT GREEN (-5500 5575);
DISPLAY INVISIBLE (-5500 5575);
FORCEPROP 1 LAST PATH I105
J 2
(-5500 5575);
DISPLAY 0.723404 (-5500 5575);
DISPLAY INVISIBLE (-5500 5575);
FORCEPROP 2 LAST CDS_LIB pure_quanta
J 0
(-5500 5575);
DISPLAY INVISIBLE (-5500 5575);
FORCEADD Q_CAP_DIFFBUS..2
R 2
(-5500 5375);
FORCEPROP 1 LAST LOCATION C468
J 2
(-5300 5375);
DISPLAY 0.723404 (-5300 5375);
PAINT GREEN (-5300 5375);
FORCEPROP 0 LAST $SEC 1
J 0
(-5300 5425);
DISPLAY 0.680851 (-5300 5425);
PAINT MONO (-5300 5425);
DISPLAY INVISIBLE (-5300 5425);
FORCEPROP 0 LAST CDS_SEC 1
J 0
(-5300 5425);
DISPLAY 0.680851 (-5300 5425);
DISPLAY INVISIBLE (-5300 5425);
FORCEPROP 0 LASTPIN (-5425 5375) $PN 1
J 0
(-5415 5385);
DISPLAY 0.680851 (-5415 5385);
PAINT MONO (-5415 5385);
FORCEPROP 0 LASTPIN (-5575 5375) $PN 2
J 2
(-5585 5385);
DISPLAY 0.680851 (-5585 5385);
PAINT MONO (-5585 5385);
FORCEPROP 2 LAST VALUE DIFF BUS_0.22UF
J 2
(-5625 5375);
DISPLAY 0.553191 (-5625 5375);
FORCEPROP 2 LAST CDS_LIB pure_quanta
J 0
(-5500 5375);
DISPLAY INVISIBLE (-5500 5375);
FORCEPROP 1 LAST PATH I106
J 2
(-5500 5375);
DISPLAY 0.723404 (-5500 5375);
DISPLAY INVISIBLE (-5500 5375);
FORCEPROP 1 LAST CDS_LMAN_SYM_OUTLINE -25,50,25,-50
J 2
(-5500 5375);
DISPLAY 0.468085 (-5500 5375);
PAINT GREEN (-5500 5375);
DISPLAY INVISIBLE (-5500 5375);
FORCEPROP 0 LAST VOLTAGE 6.3V
J 2
(-5575 5550);
DISPLAY 0.680851 (-5575 5550);
DISPLAY INVISIBLE (-5575 5550);
FORCEPROP 0 LAST TOLERANCE 20%
J 2
(-5575 5500);
DISPLAY 0.680851 (-5575 5500);
DISPLAY INVISIBLE (-5575 5500);
FORCEPROP 1 LAST PART_NUMBER SP_CH4221MEE01
J 2
(-5475 5450);
DISPLAY 0.723404 (-5475 5450);
PAINT GREEN (-5475 5450);
DISPLAY INVISIBLE (-5475 5450);
FORCEPROP 1 LAST MATERIAL X6S
J 2
(-5350 5425);
DISPLAY 0.723404 (-5350 5425);
PAINT GREEN (-5350 5425);
DISPLAY INVISIBLE (-5350 5425);
FORCEPROP 1 LAST PIN_NAMES_ROTATE True
J 2
(-5500 5375);
DISPLAY 0.489362 (-5500 5375);
PAINT GREEN (-5500 5375);
DISPLAY INVISIBLE (-5500 5375);
FORCEPROP 0 LAST PACK_TYPE C0201
J 2
(-5650 5375);
DISPLAY 0.680851 (-5650 5375);
DISPLAY INVISIBLE (-5650 5375);
FORCEADD Q_CAP_DIFFBUS..2
R 2
(-5500 5475);
FORCEPROP 1 LAST LOCATION C466
J 2
(-5250 5475);
DISPLAY 0.723404 (-5250 5475);
PAINT GREEN (-5250 5475);
FORCEPROP 0 LAST $SEC 1
J 0
(-5250 5525);
DISPLAY 0.680851 (-5250 5525);
PAINT MONO (-5250 5525);
DISPLAY INVISIBLE (-5250 5525);
FORCEPROP 0 LAST CDS_SEC 1
J 0
(-5250 5525);
DISPLAY 0.680851 (-5250 5525);
DISPLAY INVISIBLE (-5250 5525);
FORCEPROP 0 LASTPIN (-5425 5475) $PN 1
J 0
(-5415 5485);
DISPLAY 0.680851 (-5415 5485);
PAINT MONO (-5415 5485);
FORCEPROP 0 LASTPIN (-5575 5475) $PN 2
J 2
(-5585 5485);
DISPLAY 0.680851 (-5585 5485);
PAINT MONO (-5585 5485);
FORCEPROP 2 LAST VALUE DIFF BUS_0.22UF
J 2
(-5625 5475);
DISPLAY 0.553191 (-5625 5475);
FORCEPROP 2 LAST CDS_LIB pure_quanta
J 0
(-5500 5475);
DISPLAY INVISIBLE (-5500 5475);
FORCEPROP 1 LAST PATH I107
J 2
(-5500 5475);
DISPLAY 0.723404 (-5500 5475);
DISPLAY INVISIBLE (-5500 5475);
FORCEPROP 1 LAST CDS_LMAN_SYM_OUTLINE -25,50,25,-50
J 2
(-5500 5475);
DISPLAY 0.468085 (-5500 5475);
PAINT GREEN (-5500 5475);
DISPLAY INVISIBLE (-5500 5475);
FORCEPROP 0 LAST VOLTAGE 6.3V
J 2
(-5575 5650);
DISPLAY 0.680851 (-5575 5650);
DISPLAY INVISIBLE (-5575 5650);
FORCEPROP 0 LAST TOLERANCE 20%
J 2
(-5575 5600);
DISPLAY 0.680851 (-5575 5600);
DISPLAY INVISIBLE (-5575 5600);
FORCEPROP 1 LAST PART_NUMBER SP_CH4221MEE01
J 2
(-5475 5550);
DISPLAY 0.723404 (-5475 5550);
PAINT GREEN (-5475 5550);
DISPLAY INVISIBLE (-5475 5550);
FORCEPROP 1 LAST MATERIAL X6S
J 2
(-5350 5525);
DISPLAY 0.723404 (-5350 5525);
PAINT GREEN (-5350 5525);
DISPLAY INVISIBLE (-5350 5525);
FORCEPROP 1 LAST PIN_NAMES_ROTATE True
J 2
(-5500 5475);
DISPLAY 0.489362 (-5500 5475);
PAINT GREEN (-5500 5475);
DISPLAY INVISIBLE (-5500 5475);
FORCEPROP 0 LAST PACK_TYPE C0201
J 2
(-5650 5475);
DISPLAY 0.680851 (-5650 5475);
DISPLAY INVISIBLE (-5650 5475);
FORCEADD Q_CAP_DIFFBUS..2
R 2
(-5500 5425);
FORCEPROP 1 LAST LOCATION C467
J 2
(-5300 5425);
DISPLAY 0.723404 (-5300 5425);
PAINT GREEN (-5300 5425);
FORCEPROP 0 LAST $SEC 1
J 0
(-5300 5475);
DISPLAY 0.680851 (-5300 5475);
PAINT MONO (-5300 5475);
DISPLAY INVISIBLE (-5300 5475);
FORCEPROP 0 LAST CDS_SEC 1
J 0
(-5300 5475);
DISPLAY 0.680851 (-5300 5475);
DISPLAY INVISIBLE (-5300 5475);
FORCEPROP 0 LASTPIN (-5425 5425) $PN 1
J 0
(-5415 5435);
DISPLAY 0.680851 (-5415 5435);
PAINT MONO (-5415 5435);
FORCEPROP 0 LASTPIN (-5575 5425) $PN 2
J 2
(-5585 5435);
DISPLAY 0.680851 (-5585 5435);
PAINT MONO (-5585 5435);
FORCEPROP 2 LAST VALUE DIFF BUS_0.22UF
J 2
(-5625 5425);
DISPLAY 0.553191 (-5625 5425);
FORCEPROP 2 LAST CDS_LIB pure_quanta
J 0
(-5500 5425);
DISPLAY INVISIBLE (-5500 5425);
FORCEPROP 1 LAST PATH I108
J 2
(-5500 5425);
DISPLAY 0.723404 (-5500 5425);
DISPLAY INVISIBLE (-5500 5425);
FORCEPROP 1 LAST CDS_LMAN_SYM_OUTLINE -25,50,25,-50
J 2
(-5500 5425);
DISPLAY 0.468085 (-5500 5425);
PAINT GREEN (-5500 5425);
DISPLAY INVISIBLE (-5500 5425);
FORCEPROP 0 LAST VOLTAGE 6.3V
J 2
(-5575 5600);
DISPLAY 0.680851 (-5575 5600);
DISPLAY INVISIBLE (-5575 5600);
FORCEPROP 0 LAST TOLERANCE 20%
J 2
(-5575 5550);
DISPLAY 0.680851 (-5575 5550);
DISPLAY INVISIBLE (-5575 5550);
FORCEPROP 1 LAST PART_NUMBER SP_CH4221MEE01
J 2
(-5475 5500);
DISPLAY 0.723404 (-5475 5500);
PAINT GREEN (-5475 5500);
DISPLAY INVISIBLE (-5475 5500);
FORCEPROP 1 LAST MATERIAL X6S
J 2
(-5350 5475);
DISPLAY 0.723404 (-5350 5475);
PAINT GREEN (-5350 5475);
DISPLAY INVISIBLE (-5350 5475);
FORCEPROP 1 LAST PIN_NAMES_ROTATE True
J 2
(-5500 5425);
DISPLAY 0.489362 (-5500 5425);
PAINT GREEN (-5500 5425);
DISPLAY INVISIBLE (-5500 5425);
FORCEPROP 0 LAST PACK_TYPE C0201
J 2
(-5650 5425);
DISPLAY 0.680851 (-5650 5425);
DISPLAY INVISIBLE (-5650 5425);
FORCEADD Q_CAP_DIFFBUS..2
R 2
(-5500 5325);
FORCEPROP 1 LAST LOCATION C469
J 2
(-5300 5325);
DISPLAY 0.723404 (-5300 5325);
PAINT GREEN (-5300 5325);
FORCEPROP 0 LAST $SEC 1
J 0
(-5300 5375);
DISPLAY 0.680851 (-5300 5375);
PAINT MONO (-5300 5375);
DISPLAY INVISIBLE (-5300 5375);
FORCEPROP 0 LAST CDS_SEC 1
J 0
(-5300 5375);
DISPLAY 0.680851 (-5300 5375);
DISPLAY INVISIBLE (-5300 5375);
FORCEPROP 0 LASTPIN (-5425 5325) $PN 1
J 0
(-5415 5335);
DISPLAY 0.680851 (-5415 5335);
PAINT MONO (-5415 5335);
FORCEPROP 0 LASTPIN (-5575 5325) $PN 2
J 2
(-5585 5335);
DISPLAY 0.680851 (-5585 5335);
PAINT MONO (-5585 5335);
FORCEPROP 2 LAST VALUE DIFF BUS_0.22UF
J 2
(-5625 5325);
DISPLAY 0.553191 (-5625 5325);
FORCEPROP 2 LAST CDS_LIB pure_quanta
J 0
(-5500 5325);
DISPLAY INVISIBLE (-5500 5325);
FORCEPROP 1 LAST PATH I109
J 2
(-5500 5325);
DISPLAY 0.723404 (-5500 5325);
DISPLAY INVISIBLE (-5500 5325);
FORCEPROP 1 LAST CDS_LMAN_SYM_OUTLINE -25,50,25,-50
J 2
(-5500 5325);
DISPLAY 0.468085 (-5500 5325);
PAINT GREEN (-5500 5325);
DISPLAY INVISIBLE (-5500 5325);
FORCEPROP 0 LAST PACK_TYPE C0201
J 2
(-5650 5325);
DISPLAY 0.680851 (-5650 5325);
DISPLAY INVISIBLE (-5650 5325);
FORCEPROP 1 LAST PIN_NAMES_ROTATE True
J 2
(-5500 5325);
DISPLAY 0.489362 (-5500 5325);
PAINT GREEN (-5500 5325);
DISPLAY INVISIBLE (-5500 5325);
FORCEPROP 1 LAST MATERIAL X6S
J 2
(-5350 5375);
DISPLAY 0.723404 (-5350 5375);
PAINT GREEN (-5350 5375);
DISPLAY INVISIBLE (-5350 5375);
FORCEPROP 1 LAST PART_NUMBER SP_CH4221MEE01
J 2
(-5475 5400);
DISPLAY 0.723404 (-5475 5400);
PAINT GREEN (-5475 5400);
DISPLAY INVISIBLE (-5475 5400);
FORCEPROP 0 LAST TOLERANCE 20%
J 2
(-5575 5450);
DISPLAY 0.680851 (-5575 5450);
DISPLAY INVISIBLE (-5575 5450);
FORCEPROP 0 LAST VOLTAGE 6.3V
J 2
(-5575 5500);
DISPLAY 0.680851 (-5575 5500);
DISPLAY INVISIBLE (-5575 5500);
FORCEADD TAP..6
(-6375 4375);
FORCEPROP 3 LASTPIN (-6325 4375) SIG_NAME P5E_CPU0_G3_TX_DN<13>
J 0
(-6315 4385);
DISPLAY 0.659574 (-6315 4385);
PAINT MONO (-6315 4385);
DISPLAY INVISIBLE (-6315 4385);
FORCEPROP 1 LASTPIN (-6325 4375) BN 13
J 0
(-6377 4383);
DISPLAY 0.680851 (-6377 4383);
PAINT MONO (-6377 4383);
FORCEPROP 2 LAST CDS_LIB standard
J 0
(-6375 4375);
DISPLAY INVISIBLE (-6375 4375);
FORCEPROP 1 LAST PATH I11
J 0
(-6377 4375);
DISPLAY 0.872340 (-6377 4375);
PAINT GREEN (-6377 4375);
DISPLAY INVISIBLE (-6377 4375);
FORCEPROP 1 LAST HDL_TAP TRUE
J 0
(-6050 4250);
DISPLAY 0.574468 (-6050 4250);
PAINT GREEN (-6050 4250);
DISPLAY INVISIBLE (-6050 4250);
FORCEPROP 1 LAST BODY_TYPE PLUMBING
J 0
(-6375 4325);
DISPLAY 0.574468 (-6375 4325);
PAINT GREEN (-6375 4325);
DISPLAY INVISIBLE (-6375 4325);
FORCEADD Q_CAP_DIFFBUS..2
R 2
(-5500 5275);
FORCEPROP 1 LAST LOCATION C470
J 2
(-5300 5275);
DISPLAY 0.723404 (-5300 5275);
PAINT GREEN (-5300 5275);
FORCEPROP 0 LAST $SEC 1
J 0
(-5300 5325);
DISPLAY 0.680851 (-5300 5325);
PAINT MONO (-5300 5325);
DISPLAY INVISIBLE (-5300 5325);
FORCEPROP 0 LAST CDS_SEC 1
J 0
(-5300 5325);
DISPLAY 0.680851 (-5300 5325);
DISPLAY INVISIBLE (-5300 5325);
FORCEPROP 0 LASTPIN (-5425 5275) $PN 1
J 0
(-5415 5285);
DISPLAY 0.680851 (-5415 5285);
PAINT MONO (-5415 5285);
FORCEPROP 0 LASTPIN (-5575 5275) $PN 2
J 2
(-5585 5285);
DISPLAY 0.680851 (-5585 5285);
PAINT MONO (-5585 5285);
FORCEPROP 2 LAST VALUE DIFF BUS_0.22UF
J 2
(-5625 5275);
DISPLAY 0.553191 (-5625 5275);
FORCEPROP 0 LAST PACK_TYPE C0201
J 2
(-5650 5275);
DISPLAY 0.680851 (-5650 5275);
DISPLAY INVISIBLE (-5650 5275);
FORCEPROP 1 LAST PIN_NAMES_ROTATE True
J 2
(-5500 5275);
DISPLAY 0.489362 (-5500 5275);
PAINT GREEN (-5500 5275);
DISPLAY INVISIBLE (-5500 5275);
FORCEPROP 1 LAST MATERIAL X6S
J 2
(-5350 5325);
DISPLAY 0.723404 (-5350 5325);
PAINT GREEN (-5350 5325);
DISPLAY INVISIBLE (-5350 5325);
FORCEPROP 1 LAST PART_NUMBER SP_CH4221MEE01
J 2
(-5475 5350);
DISPLAY 0.723404 (-5475 5350);
PAINT GREEN (-5475 5350);
DISPLAY INVISIBLE (-5475 5350);
FORCEPROP 0 LAST TOLERANCE 20%
J 2
(-5575 5400);
DISPLAY 0.680851 (-5575 5400);
DISPLAY INVISIBLE (-5575 5400);
FORCEPROP 0 LAST VOLTAGE 6.3V
J 2
(-5575 5450);
DISPLAY 0.680851 (-5575 5450);
DISPLAY INVISIBLE (-5575 5450);
FORCEPROP 1 LAST CDS_LMAN_SYM_OUTLINE -25,50,25,-50
J 2
(-5500 5275);
DISPLAY 0.468085 (-5500 5275);
PAINT GREEN (-5500 5275);
DISPLAY INVISIBLE (-5500 5275);
FORCEPROP 1 LAST PATH I110
J 2
(-5500 5275);
DISPLAY 0.723404 (-5500 5275);
DISPLAY INVISIBLE (-5500 5275);
FORCEPROP 2 LAST CDS_LIB pure_quanta
J 0
(-5500 5275);
DISPLAY INVISIBLE (-5500 5275);
FORCEADD Q_CAP_DIFFBUS..2
R 2
(-5500 5225);
FORCEPROP 1 LAST LOCATION C471
J 2
(-5300 5225);
DISPLAY 0.723404 (-5300 5225);
PAINT GREEN (-5300 5225);
FORCEPROP 0 LAST $SEC 1
J 0
(-5300 5275);
DISPLAY 0.680851 (-5300 5275);
PAINT MONO (-5300 5275);
DISPLAY INVISIBLE (-5300 5275);
FORCEPROP 0 LAST CDS_SEC 1
J 0
(-5300 5275);
DISPLAY 0.680851 (-5300 5275);
DISPLAY INVISIBLE (-5300 5275);
FORCEPROP 0 LASTPIN (-5425 5225) $PN 1
J 0
(-5415 5235);
DISPLAY 0.680851 (-5415 5235);
PAINT MONO (-5415 5235);
FORCEPROP 0 LASTPIN (-5575 5225) $PN 2
J 2
(-5585 5235);
DISPLAY 0.680851 (-5585 5235);
PAINT MONO (-5585 5235);
FORCEPROP 2 LAST VALUE DIFF BUS_0.22UF
J 2
(-5625 5225);
DISPLAY 0.553191 (-5625 5225);
FORCEPROP 2 LAST CDS_LIB pure_quanta
J 0
(-5500 5225);
DISPLAY INVISIBLE (-5500 5225);
FORCEPROP 1 LAST PATH I111
J 2
(-5500 5225);
DISPLAY 0.723404 (-5500 5225);
DISPLAY INVISIBLE (-5500 5225);
FORCEPROP 1 LAST CDS_LMAN_SYM_OUTLINE -25,50,25,-50
J 2
(-5500 5225);
DISPLAY 0.468085 (-5500 5225);
PAINT GREEN (-5500 5225);
DISPLAY INVISIBLE (-5500 5225);
FORCEPROP 0 LAST VOLTAGE 6.3V
J 2
(-5575 5400);
DISPLAY 0.680851 (-5575 5400);
DISPLAY INVISIBLE (-5575 5400);
FORCEPROP 0 LAST TOLERANCE 20%
J 2
(-5575 5350);
DISPLAY 0.680851 (-5575 5350);
DISPLAY INVISIBLE (-5575 5350);
FORCEPROP 1 LAST PART_NUMBER SP_CH4221MEE01
J 2
(-5475 5300);
DISPLAY 0.723404 (-5475 5300);
PAINT GREEN (-5475 5300);
DISPLAY INVISIBLE (-5475 5300);
FORCEPROP 1 LAST MATERIAL X6S
J 2
(-5350 5275);
DISPLAY 0.723404 (-5350 5275);
PAINT GREEN (-5350 5275);
DISPLAY INVISIBLE (-5350 5275);
FORCEPROP 1 LAST PIN_NAMES_ROTATE True
J 2
(-5500 5225);
DISPLAY 0.489362 (-5500 5225);
PAINT GREEN (-5500 5225);
DISPLAY INVISIBLE (-5500 5225);
FORCEPROP 0 LAST PACK_TYPE C0201
J 2
(-5650 5225);
DISPLAY 0.680851 (-5650 5225);
DISPLAY INVISIBLE (-5650 5225);
FORCEADD Q_CAP_DIFFBUS..2
R 2
(-5500 5125);
FORCEPROP 1 LAST LOCATION C473
J 2
(-5300 5125);
DISPLAY 0.723404 (-5300 5125);
PAINT GREEN (-5300 5125);
FORCEPROP 0 LAST $SEC 1
J 0
(-5300 5175);
DISPLAY 0.680851 (-5300 5175);
PAINT MONO (-5300 5175);
DISPLAY INVISIBLE (-5300 5175);
FORCEPROP 0 LAST CDS_SEC 1
J 0
(-5300 5175);
DISPLAY 0.680851 (-5300 5175);
DISPLAY INVISIBLE (-5300 5175);
FORCEPROP 0 LASTPIN (-5425 5125) $PN 1
J 0
(-5415 5135);
DISPLAY 0.680851 (-5415 5135);
PAINT MONO (-5415 5135);
FORCEPROP 0 LASTPIN (-5575 5125) $PN 2
J 2
(-5585 5135);
DISPLAY 0.680851 (-5585 5135);
PAINT MONO (-5585 5135);
FORCEPROP 2 LAST VALUE DIFF BUS_0.22UF
J 2
(-5625 5125);
DISPLAY 0.553191 (-5625 5125);
FORCEPROP 0 LAST PACK_TYPE C0201
J 2
(-5650 5125);
DISPLAY 0.680851 (-5650 5125);
DISPLAY INVISIBLE (-5650 5125);
FORCEPROP 1 LAST PIN_NAMES_ROTATE True
J 2
(-5500 5125);
DISPLAY 0.489362 (-5500 5125);
PAINT GREEN (-5500 5125);
DISPLAY INVISIBLE (-5500 5125);
FORCEPROP 1 LAST MATERIAL X6S
J 2
(-5350 5175);
DISPLAY 0.723404 (-5350 5175);
PAINT GREEN (-5350 5175);
DISPLAY INVISIBLE (-5350 5175);
FORCEPROP 1 LAST PART_NUMBER SP_CH4221MEE01
J 2
(-5475 5200);
DISPLAY 0.723404 (-5475 5200);
PAINT GREEN (-5475 5200);
DISPLAY INVISIBLE (-5475 5200);
FORCEPROP 0 LAST TOLERANCE 20%
J 2
(-5575 5250);
DISPLAY 0.680851 (-5575 5250);
DISPLAY INVISIBLE (-5575 5250);
FORCEPROP 0 LAST VOLTAGE 6.3V
J 2
(-5575 5300);
DISPLAY 0.680851 (-5575 5300);
DISPLAY INVISIBLE (-5575 5300);
FORCEPROP 1 LAST CDS_LMAN_SYM_OUTLINE -25,50,25,-50
J 2
(-5500 5125);
DISPLAY 0.468085 (-5500 5125);
PAINT GREEN (-5500 5125);
DISPLAY INVISIBLE (-5500 5125);
FORCEPROP 1 LAST PATH I112
J 2
(-5500 5125);
DISPLAY 0.723404 (-5500 5125);
DISPLAY INVISIBLE (-5500 5125);
FORCEPROP 2 LAST CDS_LIB pure_quanta
J 0
(-5500 5125);
DISPLAY INVISIBLE (-5500 5125);
FORCEADD Q_CAP_DIFFBUS..2
R 2
(-5500 5175);
FORCEPROP 1 LAST LOCATION C472
J 2
(-5300 5175);
DISPLAY 0.723404 (-5300 5175);
PAINT GREEN (-5300 5175);
FORCEPROP 0 LAST $SEC 1
J 0
(-5300 5225);
DISPLAY 0.680851 (-5300 5225);
PAINT MONO (-5300 5225);
DISPLAY INVISIBLE (-5300 5225);
FORCEPROP 0 LAST CDS_SEC 1
J 0
(-5300 5225);
DISPLAY 0.680851 (-5300 5225);
DISPLAY INVISIBLE (-5300 5225);
FORCEPROP 0 LASTPIN (-5425 5175) $PN 1
J 0
(-5415 5185);
DISPLAY 0.680851 (-5415 5185);
PAINT MONO (-5415 5185);
FORCEPROP 0 LASTPIN (-5575 5175) $PN 2
J 2
(-5585 5185);
DISPLAY 0.680851 (-5585 5185);
PAINT MONO (-5585 5185);
FORCEPROP 2 LAST VALUE DIFF BUS_0.22UF
J 2
(-5625 5175);
DISPLAY 0.553191 (-5625 5175);
FORCEPROP 0 LAST PACK_TYPE C0201
J 2
(-5650 5175);
DISPLAY 0.680851 (-5650 5175);
DISPLAY INVISIBLE (-5650 5175);
FORCEPROP 1 LAST PIN_NAMES_ROTATE True
J 2
(-5500 5175);
DISPLAY 0.489362 (-5500 5175);
PAINT GREEN (-5500 5175);
DISPLAY INVISIBLE (-5500 5175);
FORCEPROP 1 LAST MATERIAL X6S
J 2
(-5350 5225);
DISPLAY 0.723404 (-5350 5225);
PAINT GREEN (-5350 5225);
DISPLAY INVISIBLE (-5350 5225);
FORCEPROP 1 LAST PART_NUMBER SP_CH4221MEE01
J 2
(-5475 5250);
DISPLAY 0.723404 (-5475 5250);
PAINT GREEN (-5475 5250);
DISPLAY INVISIBLE (-5475 5250);
FORCEPROP 0 LAST TOLERANCE 20%
J 2
(-5575 5300);
DISPLAY 0.680851 (-5575 5300);
DISPLAY INVISIBLE (-5575 5300);
FORCEPROP 0 LAST VOLTAGE 6.3V
J 2
(-5575 5350);
DISPLAY 0.680851 (-5575 5350);
DISPLAY INVISIBLE (-5575 5350);
FORCEPROP 1 LAST CDS_LMAN_SYM_OUTLINE -25,50,25,-50
J 2
(-5500 5175);
DISPLAY 0.468085 (-5500 5175);
PAINT GREEN (-5500 5175);
DISPLAY INVISIBLE (-5500 5175);
FORCEPROP 1 LAST PATH I113
J 2
(-5500 5175);
DISPLAY 0.723404 (-5500 5175);
DISPLAY INVISIBLE (-5500 5175);
FORCEPROP 2 LAST CDS_LIB pure_quanta
J 0
(-5500 5175);
DISPLAY INVISIBLE (-5500 5175);
FORCEADD Q_CAP_DIFFBUS..2
R 2
(-5500 5075);
FORCEPROP 1 LAST LOCATION C474
J 2
(-5300 5075);
DISPLAY 0.723404 (-5300 5075);
PAINT GREEN (-5300 5075);
FORCEPROP 0 LAST $SEC 1
J 0
(-5300 5125);
DISPLAY 0.680851 (-5300 5125);
PAINT MONO (-5300 5125);
DISPLAY INVISIBLE (-5300 5125);
FORCEPROP 0 LAST CDS_SEC 1
J 0
(-5300 5125);
DISPLAY 0.680851 (-5300 5125);
DISPLAY INVISIBLE (-5300 5125);
FORCEPROP 0 LASTPIN (-5425 5075) $PN 1
J 0
(-5415 5085);
DISPLAY 0.680851 (-5415 5085);
PAINT MONO (-5415 5085);
FORCEPROP 0 LASTPIN (-5575 5075) $PN 2
J 2
(-5585 5085);
DISPLAY 0.680851 (-5585 5085);
PAINT MONO (-5585 5085);
FORCEPROP 2 LAST VALUE DIFF BUS_0.22UF
J 2
(-5625 5075);
DISPLAY 0.553191 (-5625 5075);
FORCEPROP 2 LAST CDS_LIB pure_quanta
J 0
(-5500 5075);
DISPLAY INVISIBLE (-5500 5075);
FORCEPROP 1 LAST PATH I114
J 2
(-5500 5075);
DISPLAY 0.723404 (-5500 5075);
DISPLAY INVISIBLE (-5500 5075);
FORCEPROP 1 LAST CDS_LMAN_SYM_OUTLINE -25,50,25,-50
J 2
(-5500 5075);
DISPLAY 0.468085 (-5500 5075);
PAINT GREEN (-5500 5075);
DISPLAY INVISIBLE (-5500 5075);
FORCEPROP 0 LAST PACK_TYPE C0201
J 2
(-5650 5075);
DISPLAY 0.680851 (-5650 5075);
DISPLAY INVISIBLE (-5650 5075);
FORCEPROP 1 LAST PIN_NAMES_ROTATE True
J 2
(-5500 5075);
DISPLAY 0.489362 (-5500 5075);
PAINT GREEN (-5500 5075);
DISPLAY INVISIBLE (-5500 5075);
FORCEPROP 1 LAST MATERIAL X6S
J 2
(-5350 5125);
DISPLAY 0.723404 (-5350 5125);
PAINT GREEN (-5350 5125);
DISPLAY INVISIBLE (-5350 5125);
FORCEPROP 1 LAST PART_NUMBER SP_CH4221MEE01
J 2
(-5475 5150);
DISPLAY 0.723404 (-5475 5150);
PAINT GREEN (-5475 5150);
DISPLAY INVISIBLE (-5475 5150);
FORCEPROP 0 LAST TOLERANCE 20%
J 2
(-5575 5200);
DISPLAY 0.680851 (-5575 5200);
DISPLAY INVISIBLE (-5575 5200);
FORCEPROP 0 LAST VOLTAGE 6.3V
J 2
(-5575 5250);
DISPLAY 0.680851 (-5575 5250);
DISPLAY INVISIBLE (-5575 5250);
FORCEADD Q_CAP_DIFFBUS..2
R 2
(-5500 5025);
FORCEPROP 1 LAST LOCATION C475
J 2
(-5300 5025);
DISPLAY 0.723404 (-5300 5025);
PAINT GREEN (-5300 5025);
FORCEPROP 0 LAST $SEC 1
J 0
(-5300 5075);
DISPLAY 0.680851 (-5300 5075);
PAINT MONO (-5300 5075);
DISPLAY INVISIBLE (-5300 5075);
FORCEPROP 0 LAST CDS_SEC 1
J 0
(-5300 5075);
DISPLAY 0.680851 (-5300 5075);
DISPLAY INVISIBLE (-5300 5075);
FORCEPROP 0 LASTPIN (-5425 5025) $PN 1
J 0
(-5415 5035);
DISPLAY 0.680851 (-5415 5035);
PAINT MONO (-5415 5035);
FORCEPROP 0 LASTPIN (-5575 5025) $PN 2
J 2
(-5585 5035);
DISPLAY 0.680851 (-5585 5035);
PAINT MONO (-5585 5035);
FORCEPROP 2 LAST VALUE DIFF BUS_0.22UF
J 2
(-5625 5025);
DISPLAY 0.553191 (-5625 5025);
FORCEPROP 0 LAST PACK_TYPE C0201
J 2
(-5650 5025);
DISPLAY 0.680851 (-5650 5025);
DISPLAY INVISIBLE (-5650 5025);
FORCEPROP 1 LAST PIN_NAMES_ROTATE True
J 2
(-5500 5025);
DISPLAY 0.489362 (-5500 5025);
PAINT GREEN (-5500 5025);
DISPLAY INVISIBLE (-5500 5025);
FORCEPROP 1 LAST MATERIAL X6S
J 2
(-5350 5075);
DISPLAY 0.723404 (-5350 5075);
PAINT GREEN (-5350 5075);
DISPLAY INVISIBLE (-5350 5075);
FORCEPROP 1 LAST PART_NUMBER SP_CH4221MEE01
J 2
(-5475 5100);
DISPLAY 0.723404 (-5475 5100);
PAINT GREEN (-5475 5100);
DISPLAY INVISIBLE (-5475 5100);
FORCEPROP 0 LAST TOLERANCE 20%
J 2
(-5575 5150);
DISPLAY 0.680851 (-5575 5150);
DISPLAY INVISIBLE (-5575 5150);
FORCEPROP 0 LAST VOLTAGE 6.3V
J 2
(-5575 5200);
DISPLAY 0.680851 (-5575 5200);
DISPLAY INVISIBLE (-5575 5200);
FORCEPROP 1 LAST CDS_LMAN_SYM_OUTLINE -25,50,25,-50
J 2
(-5500 5025);
DISPLAY 0.468085 (-5500 5025);
PAINT GREEN (-5500 5025);
DISPLAY INVISIBLE (-5500 5025);
FORCEPROP 1 LAST PATH I115
J 2
(-5500 5025);
DISPLAY 0.723404 (-5500 5025);
DISPLAY INVISIBLE (-5500 5025);
FORCEPROP 2 LAST CDS_LIB pure_quanta
J 0
(-5500 5025);
DISPLAY INVISIBLE (-5500 5025);
FORCEADD Q_CAP_DIFFBUS..2
R 2
(-5500 4975);
FORCEPROP 1 LAST LOCATION C476
J 2
(-5300 4975);
DISPLAY 0.723404 (-5300 4975);
PAINT GREEN (-5300 4975);
FORCEPROP 0 LAST $SEC 1
J 0
(-5300 5025);
DISPLAY 0.680851 (-5300 5025);
PAINT MONO (-5300 5025);
DISPLAY INVISIBLE (-5300 5025);
FORCEPROP 0 LAST CDS_SEC 1
J 0
(-5300 5025);
DISPLAY 0.680851 (-5300 5025);
DISPLAY INVISIBLE (-5300 5025);
FORCEPROP 0 LASTPIN (-5425 4975) $PN 1
J 0
(-5415 4985);
DISPLAY 0.680851 (-5415 4985);
PAINT MONO (-5415 4985);
FORCEPROP 0 LASTPIN (-5575 4975) $PN 2
J 2
(-5585 4985);
DISPLAY 0.680851 (-5585 4985);
PAINT MONO (-5585 4985);
FORCEPROP 2 LAST VALUE DIFF BUS_0.22UF
J 2
(-5625 4975);
DISPLAY 0.553191 (-5625 4975);
FORCEPROP 0 LAST PACK_TYPE C0201
J 2
(-5650 4975);
DISPLAY 0.680851 (-5650 4975);
DISPLAY INVISIBLE (-5650 4975);
FORCEPROP 1 LAST PIN_NAMES_ROTATE True
J 2
(-5500 4975);
DISPLAY 0.489362 (-5500 4975);
PAINT GREEN (-5500 4975);
DISPLAY INVISIBLE (-5500 4975);
FORCEPROP 1 LAST MATERIAL X6S
J 2
(-5350 5025);
DISPLAY 0.723404 (-5350 5025);
PAINT GREEN (-5350 5025);
DISPLAY INVISIBLE (-5350 5025);
FORCEPROP 1 LAST PART_NUMBER SP_CH4221MEE01
J 2
(-5475 5050);
DISPLAY 0.723404 (-5475 5050);
PAINT GREEN (-5475 5050);
DISPLAY INVISIBLE (-5475 5050);
FORCEPROP 0 LAST TOLERANCE 20%
J 2
(-5575 5100);
DISPLAY 0.680851 (-5575 5100);
DISPLAY INVISIBLE (-5575 5100);
FORCEPROP 0 LAST VOLTAGE 6.3V
J 2
(-5575 5150);
DISPLAY 0.680851 (-5575 5150);
DISPLAY INVISIBLE (-5575 5150);
FORCEPROP 1 LAST PATH I116
J 2
(-5500 4975);
DISPLAY 0.723404 (-5500 4975);
DISPLAY INVISIBLE (-5500 4975);
FORCEPROP 1 LAST CDS_LMAN_SYM_OUTLINE -25,50,25,-50
J 2
(-5500 4975);
DISPLAY 0.468085 (-5500 4975);
PAINT GREEN (-5500 4975);
DISPLAY INVISIBLE (-5500 4975);
FORCEPROP 2 LAST CDS_LIB pure_quanta
J 0
(-5500 4975);
DISPLAY INVISIBLE (-5500 4975);
FORCEADD Q_CAP_DIFFBUS..2
R 2
(-5500 4925);
FORCEPROP 1 LAST LOCATION C477
J 2
(-5300 4925);
DISPLAY 0.723404 (-5300 4925);
PAINT GREEN (-5300 4925);
FORCEPROP 0 LAST $SEC 1
J 0
(-5300 4975);
DISPLAY 0.680851 (-5300 4975);
PAINT MONO (-5300 4975);
DISPLAY INVISIBLE (-5300 4975);
FORCEPROP 0 LAST CDS_SEC 1
J 0
(-5300 4975);
DISPLAY 0.680851 (-5300 4975);
DISPLAY INVISIBLE (-5300 4975);
FORCEPROP 0 LASTPIN (-5425 4925) $PN 1
J 0
(-5415 4935);
DISPLAY 0.680851 (-5415 4935);
PAINT MONO (-5415 4935);
FORCEPROP 0 LASTPIN (-5575 4925) $PN 2
J 2
(-5585 4935);
DISPLAY 0.680851 (-5585 4935);
PAINT MONO (-5585 4935);
FORCEPROP 2 LAST VALUE DIFF BUS_0.22UF
J 2
(-5625 4925);
DISPLAY 0.553191 (-5625 4925);
FORCEPROP 2 LAST CDS_LIB pure_quanta
J 0
(-5500 4925);
DISPLAY INVISIBLE (-5500 4925);
FORCEPROP 1 LAST PATH I117
J 2
(-5500 4925);
DISPLAY 0.723404 (-5500 4925);
DISPLAY INVISIBLE (-5500 4925);
FORCEPROP 1 LAST CDS_LMAN_SYM_OUTLINE -25,50,25,-50
J 2
(-5500 4925);
DISPLAY 0.468085 (-5500 4925);
PAINT GREEN (-5500 4925);
DISPLAY INVISIBLE (-5500 4925);
FORCEPROP 0 LAST PACK_TYPE C0201
J 2
(-5650 4925);
DISPLAY 0.680851 (-5650 4925);
DISPLAY INVISIBLE (-5650 4925);
FORCEPROP 1 LAST PIN_NAMES_ROTATE True
J 2
(-5500 4925);
DISPLAY 0.489362 (-5500 4925);
PAINT GREEN (-5500 4925);
DISPLAY INVISIBLE (-5500 4925);
FORCEPROP 1 LAST MATERIAL X6S
J 2
(-5350 4975);
DISPLAY 0.723404 (-5350 4975);
PAINT GREEN (-5350 4975);
DISPLAY INVISIBLE (-5350 4975);
FORCEPROP 1 LAST PART_NUMBER SP_CH4221MEE01
J 2
(-5475 5000);
DISPLAY 0.723404 (-5475 5000);
PAINT GREEN (-5475 5000);
DISPLAY INVISIBLE (-5475 5000);
FORCEPROP 0 LAST TOLERANCE 20%
J 2
(-5575 5050);
DISPLAY 0.680851 (-5575 5050);
DISPLAY INVISIBLE (-5575 5050);
FORCEPROP 0 LAST VOLTAGE 6.3V
J 2
(-5575 5100);
DISPLAY 0.680851 (-5575 5100);
DISPLAY INVISIBLE (-5575 5100);
FORCEADD Q_CAP_DIFFBUS..2
R 2
(-5500 4875);
FORCEPROP 1 LAST LOCATION C478
J 2
(-5300 4875);
DISPLAY 0.723404 (-5300 4875);
PAINT GREEN (-5300 4875);
FORCEPROP 0 LAST $SEC 1
J 0
(-5300 4925);
DISPLAY 0.680851 (-5300 4925);
PAINT MONO (-5300 4925);
DISPLAY INVISIBLE (-5300 4925);
FORCEPROP 0 LAST CDS_SEC 1
J 0
(-5300 4925);
DISPLAY 0.680851 (-5300 4925);
DISPLAY INVISIBLE (-5300 4925);
FORCEPROP 0 LASTPIN (-5425 4875) $PN 1
J 0
(-5415 4885);
DISPLAY 0.680851 (-5415 4885);
PAINT MONO (-5415 4885);
FORCEPROP 0 LASTPIN (-5575 4875) $PN 2
J 2
(-5585 4885);
DISPLAY 0.680851 (-5585 4885);
PAINT MONO (-5585 4885);
FORCEPROP 2 LAST VALUE DIFF BUS_0.22UF
J 2
(-5625 4875);
DISPLAY 0.553191 (-5625 4875);
FORCEPROP 2 LAST CDS_LIB pure_quanta
J 0
(-5500 4875);
DISPLAY INVISIBLE (-5500 4875);
FORCEPROP 1 LAST PATH I118
J 2
(-5500 4875);
DISPLAY 0.723404 (-5500 4875);
DISPLAY INVISIBLE (-5500 4875);
FORCEPROP 1 LAST CDS_LMAN_SYM_OUTLINE -25,50,25,-50
J 2
(-5500 4875);
DISPLAY 0.468085 (-5500 4875);
PAINT GREEN (-5500 4875);
DISPLAY INVISIBLE (-5500 4875);
FORCEPROP 0 LAST VOLTAGE 6.3V
J 2
(-5575 5050);
DISPLAY 0.680851 (-5575 5050);
DISPLAY INVISIBLE (-5575 5050);
FORCEPROP 0 LAST TOLERANCE 20%
J 2
(-5575 5000);
DISPLAY 0.680851 (-5575 5000);
DISPLAY INVISIBLE (-5575 5000);
FORCEPROP 1 LAST PART_NUMBER SP_CH4221MEE01
J 2
(-5475 4950);
DISPLAY 0.723404 (-5475 4950);
PAINT GREEN (-5475 4950);
DISPLAY INVISIBLE (-5475 4950);
FORCEPROP 1 LAST MATERIAL X6S
J 2
(-5350 4925);
DISPLAY 0.723404 (-5350 4925);
PAINT GREEN (-5350 4925);
DISPLAY INVISIBLE (-5350 4925);
FORCEPROP 1 LAST PIN_NAMES_ROTATE True
J 2
(-5500 4875);
DISPLAY 0.489362 (-5500 4875);
PAINT GREEN (-5500 4875);
DISPLAY INVISIBLE (-5500 4875);
FORCEPROP 0 LAST PACK_TYPE C0201
J 2
(-5650 4875);
DISPLAY 0.680851 (-5650 4875);
DISPLAY INVISIBLE (-5650 4875);
FORCEADD Q_CAP_DIFFBUS..2
R 2
(-5500 4825);
FORCEPROP 1 LAST LOCATION C479
J 2
(-5300 4825);
DISPLAY 0.723404 (-5300 4825);
PAINT GREEN (-5300 4825);
FORCEPROP 0 LAST $SEC 1
J 0
(-5300 4875);
DISPLAY 0.680851 (-5300 4875);
PAINT MONO (-5300 4875);
DISPLAY INVISIBLE (-5300 4875);
FORCEPROP 0 LAST CDS_SEC 1
J 0
(-5300 4875);
DISPLAY 0.680851 (-5300 4875);
DISPLAY INVISIBLE (-5300 4875);
FORCEPROP 0 LASTPIN (-5425 4825) $PN 1
J 0
(-5415 4835);
DISPLAY 0.680851 (-5415 4835);
PAINT MONO (-5415 4835);
FORCEPROP 0 LASTPIN (-5575 4825) $PN 2
J 2
(-5585 4835);
DISPLAY 0.680851 (-5585 4835);
PAINT MONO (-5585 4835);
FORCEPROP 2 LAST VALUE DIFF BUS_0.22UF
J 2
(-5625 4825);
DISPLAY 0.553191 (-5625 4825);
FORCEPROP 0 LAST PACK_TYPE C0201
J 2
(-5650 4825);
DISPLAY 0.680851 (-5650 4825);
DISPLAY INVISIBLE (-5650 4825);
FORCEPROP 1 LAST PIN_NAMES_ROTATE True
J 2
(-5500 4825);
DISPLAY 0.489362 (-5500 4825);
PAINT GREEN (-5500 4825);
DISPLAY INVISIBLE (-5500 4825);
FORCEPROP 1 LAST MATERIAL X6S
J 2
(-5350 4875);
DISPLAY 0.723404 (-5350 4875);
PAINT GREEN (-5350 4875);
DISPLAY INVISIBLE (-5350 4875);
FORCEPROP 1 LAST PART_NUMBER SP_CH4221MEE01
J 2
(-5475 4900);
DISPLAY 0.723404 (-5475 4900);
PAINT GREEN (-5475 4900);
DISPLAY INVISIBLE (-5475 4900);
FORCEPROP 0 LAST TOLERANCE 20%
J 2
(-5575 4950);
DISPLAY 0.680851 (-5575 4950);
DISPLAY INVISIBLE (-5575 4950);
FORCEPROP 0 LAST VOLTAGE 6.3V
J 2
(-5575 5000);
DISPLAY 0.680851 (-5575 5000);
DISPLAY INVISIBLE (-5575 5000);
FORCEPROP 1 LAST CDS_LMAN_SYM_OUTLINE -25,50,25,-50
J 2
(-5500 4825);
DISPLAY 0.468085 (-5500 4825);
PAINT GREEN (-5500 4825);
DISPLAY INVISIBLE (-5500 4825);
FORCEPROP 1 LAST PATH I119
J 2
(-5500 4825);
DISPLAY 0.723404 (-5500 4825);
DISPLAY INVISIBLE (-5500 4825);
FORCEPROP 2 LAST CDS_LIB pure_quanta
J 0
(-5500 4825);
DISPLAY INVISIBLE (-5500 4825);
FORCEADD TAP..6
(-6225 4325);
FORCEPROP 3 LASTPIN (-6175 4325) SIG_NAME P5E_CPU0_G3_TX_DP<14>
J 0
(-6165 4335);
DISPLAY 0.659574 (-6165 4335);
PAINT MONO (-6165 4335);
DISPLAY INVISIBLE (-6165 4335);
FORCEPROP 1 LASTPIN (-6175 4325) BN 14
J 0
(-6227 4333);
DISPLAY 0.680851 (-6227 4333);
PAINT MONO (-6227 4333);
FORCEPROP 2 LAST CDS_LIB standard
J 0
(-6225 4325);
DISPLAY INVISIBLE (-6225 4325);
FORCEPROP 1 LAST PATH I12
J 0
(-6227 4325);
DISPLAY 0.872340 (-6227 4325);
PAINT GREEN (-6227 4325);
DISPLAY INVISIBLE (-6227 4325);
FORCEPROP 1 LAST HDL_TAP TRUE
J 0
(-5900 4200);
DISPLAY 0.574468 (-5900 4200);
PAINT GREEN (-5900 4200);
DISPLAY INVISIBLE (-5900 4200);
FORCEPROP 1 LAST BODY_TYPE PLUMBING
J 0
(-6225 4275);
DISPLAY 0.574468 (-6225 4275);
PAINT GREEN (-6225 4275);
DISPLAY INVISIBLE (-6225 4275);
FORCEADD Q_CAP_DIFFBUS..2
R 2
(-5500 4775);
FORCEPROP 1 LAST LOCATION C480
J 2
(-5300 4775);
DISPLAY 0.723404 (-5300 4775);
PAINT GREEN (-5300 4775);
FORCEPROP 0 LAST $SEC 1
J 0
(-5300 4825);
DISPLAY 0.680851 (-5300 4825);
PAINT MONO (-5300 4825);
DISPLAY INVISIBLE (-5300 4825);
FORCEPROP 0 LAST CDS_SEC 1
J 0
(-5300 4825);
DISPLAY 0.680851 (-5300 4825);
DISPLAY INVISIBLE (-5300 4825);
FORCEPROP 0 LASTPIN (-5425 4775) $PN 1
J 0
(-5415 4785);
DISPLAY 0.680851 (-5415 4785);
PAINT MONO (-5415 4785);
FORCEPROP 0 LASTPIN (-5575 4775) $PN 2
J 2
(-5585 4785);
DISPLAY 0.680851 (-5585 4785);
PAINT MONO (-5585 4785);
FORCEPROP 2 LAST VALUE DIFF BUS_0.22UF
J 2
(-5625 4775);
DISPLAY 0.553191 (-5625 4775);
FORCEPROP 0 LAST PACK_TYPE C0201
J 2
(-5650 4775);
DISPLAY 0.680851 (-5650 4775);
DISPLAY INVISIBLE (-5650 4775);
FORCEPROP 1 LAST PIN_NAMES_ROTATE True
J 2
(-5500 4775);
DISPLAY 0.489362 (-5500 4775);
PAINT GREEN (-5500 4775);
DISPLAY INVISIBLE (-5500 4775);
FORCEPROP 1 LAST MATERIAL X6S
J 2
(-5350 4825);
DISPLAY 0.723404 (-5350 4825);
PAINT GREEN (-5350 4825);
DISPLAY INVISIBLE (-5350 4825);
FORCEPROP 1 LAST PART_NUMBER SP_CH4221MEE01
J 2
(-5475 4850);
DISPLAY 0.723404 (-5475 4850);
PAINT GREEN (-5475 4850);
DISPLAY INVISIBLE (-5475 4850);
FORCEPROP 0 LAST TOLERANCE 20%
J 2
(-5575 4900);
DISPLAY 0.680851 (-5575 4900);
DISPLAY INVISIBLE (-5575 4900);
FORCEPROP 0 LAST VOLTAGE 6.3V
J 2
(-5575 4950);
DISPLAY 0.680851 (-5575 4950);
DISPLAY INVISIBLE (-5575 4950);
FORCEPROP 1 LAST PATH I120
J 2
(-5500 4775);
DISPLAY 0.723404 (-5500 4775);
DISPLAY INVISIBLE (-5500 4775);
FORCEPROP 1 LAST CDS_LMAN_SYM_OUTLINE -25,50,25,-50
J 2
(-5500 4775);
DISPLAY 0.468085 (-5500 4775);
PAINT GREEN (-5500 4775);
DISPLAY INVISIBLE (-5500 4775);
FORCEPROP 2 LAST CDS_LIB pure_quanta
J 0
(-5500 4775);
DISPLAY INVISIBLE (-5500 4775);
FORCEADD Q_CAP_DIFFBUS..2
R 2
(-5500 4725);
FORCEPROP 1 LAST LOCATION C481
J 2
(-5275 4725);
DISPLAY 0.723404 (-5275 4725);
PAINT GREEN (-5275 4725);
FORCEPROP 0 LAST $SEC 1
J 0
(-5275 4775);
DISPLAY 0.680851 (-5275 4775);
PAINT MONO (-5275 4775);
DISPLAY INVISIBLE (-5275 4775);
FORCEPROP 0 LAST CDS_SEC 1
J 0
(-5275 4775);
DISPLAY 0.680851 (-5275 4775);
DISPLAY INVISIBLE (-5275 4775);
FORCEPROP 0 LASTPIN (-5425 4725) $PN 1
J 0
(-5415 4735);
DISPLAY 0.680851 (-5415 4735);
PAINT MONO (-5415 4735);
FORCEPROP 0 LASTPIN (-5575 4725) $PN 2
J 2
(-5585 4735);
DISPLAY 0.680851 (-5585 4735);
PAINT MONO (-5585 4735);
FORCEPROP 2 LAST VALUE DIFF BUS_0.22UF
J 2
(-5625 4725);
DISPLAY 0.553191 (-5625 4725);
FORCEPROP 2 LAST CDS_LIB pure_quanta
J 0
(-5500 4725);
DISPLAY INVISIBLE (-5500 4725);
FORCEPROP 1 LAST PATH I121
J 2
(-5500 4725);
DISPLAY 0.723404 (-5500 4725);
DISPLAY INVISIBLE (-5500 4725);
FORCEPROP 1 LAST CDS_LMAN_SYM_OUTLINE -25,50,25,-50
J 2
(-5500 4725);
DISPLAY 0.468085 (-5500 4725);
PAINT GREEN (-5500 4725);
DISPLAY INVISIBLE (-5500 4725);
FORCEPROP 0 LAST PACK_TYPE C0201
J 2
(-5650 4725);
DISPLAY 0.680851 (-5650 4725);
DISPLAY INVISIBLE (-5650 4725);
FORCEPROP 1 LAST PIN_NAMES_ROTATE True
J 2
(-5500 4725);
DISPLAY 0.489362 (-5500 4725);
PAINT GREEN (-5500 4725);
DISPLAY INVISIBLE (-5500 4725);
FORCEPROP 1 LAST MATERIAL X6S
J 2
(-5350 4775);
DISPLAY 0.723404 (-5350 4775);
PAINT GREEN (-5350 4775);
DISPLAY INVISIBLE (-5350 4775);
FORCEPROP 1 LAST PART_NUMBER SP_CH4221MEE01
J 2
(-5475 4800);
DISPLAY 0.723404 (-5475 4800);
PAINT GREEN (-5475 4800);
DISPLAY INVISIBLE (-5475 4800);
FORCEPROP 0 LAST TOLERANCE 20%
J 2
(-5575 4850);
DISPLAY 0.680851 (-5575 4850);
DISPLAY INVISIBLE (-5575 4850);
FORCEPROP 0 LAST VOLTAGE 6.3V
J 2
(-5575 4900);
DISPLAY 0.680851 (-5575 4900);
DISPLAY INVISIBLE (-5575 4900);
FORCEADD Q_CAP_DIFFBUS..2
R 2
(-5500 4675);
FORCEPROP 1 LAST LOCATION C482
J 2
(-5300 4675);
DISPLAY 0.723404 (-5300 4675);
PAINT GREEN (-5300 4675);
FORCEPROP 0 LAST $SEC 1
J 0
(-5300 4725);
DISPLAY 0.680851 (-5300 4725);
PAINT MONO (-5300 4725);
DISPLAY INVISIBLE (-5300 4725);
FORCEPROP 0 LAST CDS_SEC 1
J 0
(-5300 4725);
DISPLAY 0.680851 (-5300 4725);
DISPLAY INVISIBLE (-5300 4725);
FORCEPROP 0 LASTPIN (-5425 4675) $PN 1
J 0
(-5415 4685);
DISPLAY 0.680851 (-5415 4685);
PAINT MONO (-5415 4685);
FORCEPROP 0 LASTPIN (-5575 4675) $PN 2
J 2
(-5585 4685);
DISPLAY 0.680851 (-5585 4685);
PAINT MONO (-5585 4685);
FORCEPROP 2 LAST VALUE DIFF BUS_0.22UF
J 2
(-5625 4675);
DISPLAY 0.553191 (-5625 4675);
FORCEPROP 2 LAST CDS_LIB pure_quanta
J 0
(-5500 4675);
DISPLAY INVISIBLE (-5500 4675);
FORCEPROP 1 LAST PATH I122
J 2
(-5500 4675);
DISPLAY 0.723404 (-5500 4675);
DISPLAY INVISIBLE (-5500 4675);
FORCEPROP 1 LAST CDS_LMAN_SYM_OUTLINE -25,50,25,-50
J 2
(-5500 4675);
DISPLAY 0.468085 (-5500 4675);
PAINT GREEN (-5500 4675);
DISPLAY INVISIBLE (-5500 4675);
FORCEPROP 0 LAST VOLTAGE 6.3V
J 2
(-5575 4850);
DISPLAY 0.680851 (-5575 4850);
DISPLAY INVISIBLE (-5575 4850);
FORCEPROP 0 LAST TOLERANCE 20%
J 2
(-5575 4800);
DISPLAY 0.680851 (-5575 4800);
DISPLAY INVISIBLE (-5575 4800);
FORCEPROP 1 LAST PART_NUMBER SP_CH4221MEE01
J 2
(-5475 4750);
DISPLAY 0.723404 (-5475 4750);
PAINT GREEN (-5475 4750);
DISPLAY INVISIBLE (-5475 4750);
FORCEPROP 1 LAST MATERIAL X6S
J 2
(-5350 4725);
DISPLAY 0.723404 (-5350 4725);
PAINT GREEN (-5350 4725);
DISPLAY INVISIBLE (-5350 4725);
FORCEPROP 1 LAST PIN_NAMES_ROTATE True
J 2
(-5500 4675);
DISPLAY 0.489362 (-5500 4675);
PAINT GREEN (-5500 4675);
DISPLAY INVISIBLE (-5500 4675);
FORCEPROP 0 LAST PACK_TYPE C0201
J 2
(-5650 4675);
DISPLAY 0.680851 (-5650 4675);
DISPLAY INVISIBLE (-5650 4675);
FORCEADD Q_CAP_DIFFBUS..2
R 2
(-5500 4625);
FORCEPROP 1 LAST LOCATION C483
J 2
(-5275 4625);
DISPLAY 0.723404 (-5275 4625);
PAINT GREEN (-5275 4625);
FORCEPROP 0 LAST $SEC 1
J 0
(-5275 4675);
DISPLAY 0.680851 (-5275 4675);
PAINT MONO (-5275 4675);
DISPLAY INVISIBLE (-5275 4675);
FORCEPROP 0 LAST CDS_SEC 1
J 0
(-5275 4675);
DISPLAY 0.680851 (-5275 4675);
DISPLAY INVISIBLE (-5275 4675);
FORCEPROP 0 LASTPIN (-5425 4625) $PN 1
J 0
(-5415 4635);
DISPLAY 0.680851 (-5415 4635);
PAINT MONO (-5415 4635);
FORCEPROP 0 LASTPIN (-5575 4625) $PN 2
J 2
(-5585 4635);
DISPLAY 0.680851 (-5585 4635);
PAINT MONO (-5585 4635);
FORCEPROP 2 LAST VALUE DIFF BUS_0.22UF
J 2
(-5625 4625);
DISPLAY 0.553191 (-5625 4625);
FORCEPROP 0 LAST PACK_TYPE C0201
J 2
(-5650 4625);
DISPLAY 0.680851 (-5650 4625);
DISPLAY INVISIBLE (-5650 4625);
FORCEPROP 1 LAST PIN_NAMES_ROTATE True
J 2
(-5500 4625);
DISPLAY 0.489362 (-5500 4625);
PAINT GREEN (-5500 4625);
DISPLAY INVISIBLE (-5500 4625);
FORCEPROP 1 LAST MATERIAL X6S
J 2
(-5350 4675);
DISPLAY 0.723404 (-5350 4675);
PAINT GREEN (-5350 4675);
DISPLAY INVISIBLE (-5350 4675);
FORCEPROP 1 LAST PART_NUMBER SP_CH4221MEE01
J 2
(-5475 4700);
DISPLAY 0.723404 (-5475 4700);
PAINT GREEN (-5475 4700);
DISPLAY INVISIBLE (-5475 4700);
FORCEPROP 0 LAST TOLERANCE 20%
J 2
(-5575 4750);
DISPLAY 0.680851 (-5575 4750);
DISPLAY INVISIBLE (-5575 4750);
FORCEPROP 0 LAST VOLTAGE 6.3V
J 2
(-5575 4800);
DISPLAY 0.680851 (-5575 4800);
DISPLAY INVISIBLE (-5575 4800);
FORCEPROP 1 LAST CDS_LMAN_SYM_OUTLINE -25,50,25,-50
J 2
(-5500 4625);
DISPLAY 0.468085 (-5500 4625);
PAINT GREEN (-5500 4625);
DISPLAY INVISIBLE (-5500 4625);
FORCEPROP 1 LAST PATH I123
J 2
(-5500 4625);
DISPLAY 0.723404 (-5500 4625);
DISPLAY INVISIBLE (-5500 4625);
FORCEPROP 2 LAST CDS_LIB pure_quanta
J 0
(-5500 4625);
DISPLAY INVISIBLE (-5500 4625);
FORCEADD Q_CAP_DIFFBUS..2
R 2
(-5500 4575);
FORCEPROP 1 LAST LOCATION C484
J 2
(-5275 4575);
DISPLAY 0.723404 (-5275 4575);
PAINT GREEN (-5275 4575);
FORCEPROP 0 LAST $SEC 1
J 0
(-5275 4625);
DISPLAY 0.680851 (-5275 4625);
PAINT MONO (-5275 4625);
DISPLAY INVISIBLE (-5275 4625);
FORCEPROP 0 LAST CDS_SEC 1
J 0
(-5275 4625);
DISPLAY 0.680851 (-5275 4625);
DISPLAY INVISIBLE (-5275 4625);
FORCEPROP 0 LASTPIN (-5425 4575) $PN 1
J 0
(-5415 4585);
DISPLAY 0.680851 (-5415 4585);
PAINT MONO (-5415 4585);
FORCEPROP 0 LASTPIN (-5575 4575) $PN 2
J 2
(-5585 4585);
DISPLAY 0.680851 (-5585 4585);
PAINT MONO (-5585 4585);
FORCEPROP 2 LAST VALUE DIFF BUS_0.22UF
J 2
(-5625 4575);
DISPLAY 0.553191 (-5625 4575);
FORCEPROP 0 LAST PACK_TYPE C0201
J 2
(-5650 4575);
DISPLAY 0.680851 (-5650 4575);
DISPLAY INVISIBLE (-5650 4575);
FORCEPROP 1 LAST PIN_NAMES_ROTATE True
J 2
(-5500 4575);
DISPLAY 0.489362 (-5500 4575);
PAINT GREEN (-5500 4575);
DISPLAY INVISIBLE (-5500 4575);
FORCEPROP 1 LAST MATERIAL X6S
J 2
(-5350 4625);
DISPLAY 0.723404 (-5350 4625);
PAINT GREEN (-5350 4625);
DISPLAY INVISIBLE (-5350 4625);
FORCEPROP 1 LAST PART_NUMBER SP_CH4221MEE01
J 2
(-5475 4650);
DISPLAY 0.723404 (-5475 4650);
PAINT GREEN (-5475 4650);
DISPLAY INVISIBLE (-5475 4650);
FORCEPROP 0 LAST TOLERANCE 20%
J 2
(-5575 4700);
DISPLAY 0.680851 (-5575 4700);
DISPLAY INVISIBLE (-5575 4700);
FORCEPROP 0 LAST VOLTAGE 6.3V
J 2
(-5575 4750);
DISPLAY 0.680851 (-5575 4750);
DISPLAY INVISIBLE (-5575 4750);
FORCEPROP 1 LAST CDS_LMAN_SYM_OUTLINE -25,50,25,-50
J 2
(-5500 4575);
DISPLAY 0.468085 (-5500 4575);
PAINT GREEN (-5500 4575);
DISPLAY INVISIBLE (-5500 4575);
FORCEPROP 1 LAST PATH I124
J 2
(-5500 4575);
DISPLAY 0.723404 (-5500 4575);
DISPLAY INVISIBLE (-5500 4575);
FORCEPROP 2 LAST CDS_LIB pure_quanta
J 0
(-5500 4575);
DISPLAY INVISIBLE (-5500 4575);
FORCEADD Q_CAP_DIFFBUS..2
R 2
(-5500 4525);
FORCEPROP 1 LAST LOCATION C485
J 2
(-5300 4525);
DISPLAY 0.723404 (-5300 4525);
PAINT GREEN (-5300 4525);
FORCEPROP 0 LAST $SEC 1
J 0
(-5300 4575);
DISPLAY 0.680851 (-5300 4575);
PAINT MONO (-5300 4575);
DISPLAY INVISIBLE (-5300 4575);
FORCEPROP 0 LAST CDS_SEC 1
J 0
(-5300 4575);
DISPLAY 0.680851 (-5300 4575);
DISPLAY INVISIBLE (-5300 4575);
FORCEPROP 0 LASTPIN (-5425 4525) $PN 1
J 0
(-5415 4535);
DISPLAY 0.680851 (-5415 4535);
PAINT MONO (-5415 4535);
FORCEPROP 0 LASTPIN (-5575 4525) $PN 2
J 2
(-5585 4535);
DISPLAY 0.680851 (-5585 4535);
PAINT MONO (-5585 4535);
FORCEPROP 2 LAST VALUE DIFF BUS_0.22UF
J 2
(-5625 4525);
DISPLAY 0.553191 (-5625 4525);
FORCEPROP 0 LAST PACK_TYPE C0201
J 2
(-5650 4525);
DISPLAY 0.680851 (-5650 4525);
DISPLAY INVISIBLE (-5650 4525);
FORCEPROP 1 LAST PIN_NAMES_ROTATE True
J 2
(-5500 4525);
DISPLAY 0.489362 (-5500 4525);
PAINT GREEN (-5500 4525);
DISPLAY INVISIBLE (-5500 4525);
FORCEPROP 1 LAST MATERIAL X6S
J 2
(-5350 4575);
DISPLAY 0.723404 (-5350 4575);
PAINT GREEN (-5350 4575);
DISPLAY INVISIBLE (-5350 4575);
FORCEPROP 1 LAST PART_NUMBER SP_CH4221MEE01
J 2
(-5475 4600);
DISPLAY 0.723404 (-5475 4600);
PAINT GREEN (-5475 4600);
DISPLAY INVISIBLE (-5475 4600);
FORCEPROP 0 LAST TOLERANCE 20%
J 2
(-5575 4650);
DISPLAY 0.680851 (-5575 4650);
DISPLAY INVISIBLE (-5575 4650);
FORCEPROP 0 LAST VOLTAGE 6.3V
J 2
(-5575 4700);
DISPLAY 0.680851 (-5575 4700);
DISPLAY INVISIBLE (-5575 4700);
FORCEPROP 1 LAST CDS_LMAN_SYM_OUTLINE -25,50,25,-50
J 2
(-5500 4525);
DISPLAY 0.468085 (-5500 4525);
PAINT GREEN (-5500 4525);
DISPLAY INVISIBLE (-5500 4525);
FORCEPROP 1 LAST PATH I125
J 2
(-5500 4525);
DISPLAY 0.723404 (-5500 4525);
DISPLAY INVISIBLE (-5500 4525);
FORCEPROP 2 LAST CDS_LIB pure_quanta
J 0
(-5500 4525);
DISPLAY INVISIBLE (-5500 4525);
FORCEADD Q_CAP_DIFFBUS..2
R 2
(-5500 4475);
FORCEPROP 1 LAST LOCATION C486
J 2
(-5275 4475);
DISPLAY 0.723404 (-5275 4475);
PAINT GREEN (-5275 4475);
FORCEPROP 0 LAST $SEC 1
J 0
(-5275 4525);
DISPLAY 0.680851 (-5275 4525);
PAINT MONO (-5275 4525);
DISPLAY INVISIBLE (-5275 4525);
FORCEPROP 0 LAST CDS_SEC 1
J 0
(-5275 4525);
DISPLAY 0.680851 (-5275 4525);
DISPLAY INVISIBLE (-5275 4525);
FORCEPROP 0 LASTPIN (-5425 4475) $PN 1
J 0
(-5415 4485);
DISPLAY 0.680851 (-5415 4485);
PAINT MONO (-5415 4485);
FORCEPROP 0 LASTPIN (-5575 4475) $PN 2
J 2
(-5585 4485);
DISPLAY 0.680851 (-5585 4485);
PAINT MONO (-5585 4485);
FORCEPROP 2 LAST VALUE DIFF BUS_0.22UF
J 2
(-5625 4475);
DISPLAY 0.553191 (-5625 4475);
FORCEPROP 0 LAST PACK_TYPE C0201
J 2
(-5650 4475);
DISPLAY 0.680851 (-5650 4475);
DISPLAY INVISIBLE (-5650 4475);
FORCEPROP 1 LAST PIN_NAMES_ROTATE True
J 2
(-5500 4475);
DISPLAY 0.489362 (-5500 4475);
PAINT GREEN (-5500 4475);
DISPLAY INVISIBLE (-5500 4475);
FORCEPROP 1 LAST MATERIAL X6S
J 2
(-5350 4525);
DISPLAY 0.723404 (-5350 4525);
PAINT GREEN (-5350 4525);
DISPLAY INVISIBLE (-5350 4525);
FORCEPROP 1 LAST PART_NUMBER SP_CH4221MEE01
J 2
(-5475 4550);
DISPLAY 0.723404 (-5475 4550);
PAINT GREEN (-5475 4550);
DISPLAY INVISIBLE (-5475 4550);
FORCEPROP 0 LAST TOLERANCE 20%
J 2
(-5575 4600);
DISPLAY 0.680851 (-5575 4600);
DISPLAY INVISIBLE (-5575 4600);
FORCEPROP 0 LAST VOLTAGE 6.3V
J 2
(-5575 4650);
DISPLAY 0.680851 (-5575 4650);
DISPLAY INVISIBLE (-5575 4650);
FORCEPROP 1 LAST CDS_LMAN_SYM_OUTLINE -25,50,25,-50
J 2
(-5500 4475);
DISPLAY 0.468085 (-5500 4475);
PAINT GREEN (-5500 4475);
DISPLAY INVISIBLE (-5500 4475);
FORCEPROP 1 LAST PATH I126
J 2
(-5500 4475);
DISPLAY 0.723404 (-5500 4475);
DISPLAY INVISIBLE (-5500 4475);
FORCEPROP 2 LAST CDS_LIB pure_quanta
J 0
(-5500 4475);
DISPLAY INVISIBLE (-5500 4475);
FORCEADD Q_CAP_DIFFBUS..2
R 2
(-5500 4425);
FORCEPROP 1 LAST LOCATION C487
J 2
(-5275 4425);
DISPLAY 0.723404 (-5275 4425);
PAINT GREEN (-5275 4425);
FORCEPROP 0 LAST $SEC 1
J 0
(-5275 4475);
DISPLAY 0.680851 (-5275 4475);
PAINT MONO (-5275 4475);
DISPLAY INVISIBLE (-5275 4475);
FORCEPROP 0 LAST CDS_SEC 1
J 0
(-5275 4475);
DISPLAY 0.680851 (-5275 4475);
DISPLAY INVISIBLE (-5275 4475);
FORCEPROP 0 LASTPIN (-5425 4425) $PN 1
J 0
(-5415 4435);
DISPLAY 0.680851 (-5415 4435);
PAINT MONO (-5415 4435);
FORCEPROP 0 LASTPIN (-5575 4425) $PN 2
J 2
(-5585 4435);
DISPLAY 0.680851 (-5585 4435);
PAINT MONO (-5585 4435);
FORCEPROP 2 LAST VALUE DIFF BUS_0.22UF
J 2
(-5625 4425);
DISPLAY 0.553191 (-5625 4425);
FORCEPROP 0 LAST PACK_TYPE C0201
J 2
(-5650 4425);
DISPLAY 0.680851 (-5650 4425);
DISPLAY INVISIBLE (-5650 4425);
FORCEPROP 1 LAST PIN_NAMES_ROTATE True
J 2
(-5500 4425);
DISPLAY 0.489362 (-5500 4425);
PAINT GREEN (-5500 4425);
DISPLAY INVISIBLE (-5500 4425);
FORCEPROP 1 LAST MATERIAL X6S
J 2
(-5350 4475);
DISPLAY 0.723404 (-5350 4475);
PAINT GREEN (-5350 4475);
DISPLAY INVISIBLE (-5350 4475);
FORCEPROP 1 LAST PART_NUMBER SP_CH4221MEE01
J 2
(-5475 4500);
DISPLAY 0.723404 (-5475 4500);
PAINT GREEN (-5475 4500);
DISPLAY INVISIBLE (-5475 4500);
FORCEPROP 0 LAST TOLERANCE 20%
J 2
(-5575 4550);
DISPLAY 0.680851 (-5575 4550);
DISPLAY INVISIBLE (-5575 4550);
FORCEPROP 0 LAST VOLTAGE 6.3V
J 2
(-5575 4600);
DISPLAY 0.680851 (-5575 4600);
DISPLAY INVISIBLE (-5575 4600);
FORCEPROP 1 LAST CDS_LMAN_SYM_OUTLINE -25,50,25,-50
J 2
(-5500 4425);
DISPLAY 0.468085 (-5500 4425);
PAINT GREEN (-5500 4425);
DISPLAY INVISIBLE (-5500 4425);
FORCEPROP 1 LAST PATH I127
J 2
(-5500 4425);
DISPLAY 0.723404 (-5500 4425);
DISPLAY INVISIBLE (-5500 4425);
FORCEPROP 2 LAST CDS_LIB pure_quanta
J 0
(-5500 4425);
DISPLAY INVISIBLE (-5500 4425);
FORCEADD Q_CAP_DIFFBUS..2
R 2
(-5500 4375);
FORCEPROP 1 LAST LOCATION C488
J 2
(-5275 4375);
DISPLAY 0.723404 (-5275 4375);
PAINT GREEN (-5275 4375);
FORCEPROP 0 LAST $SEC 1
J 0
(-5275 4425);
DISPLAY 0.680851 (-5275 4425);
PAINT MONO (-5275 4425);
DISPLAY INVISIBLE (-5275 4425);
FORCEPROP 0 LAST CDS_SEC 1
J 0
(-5275 4425);
DISPLAY 0.680851 (-5275 4425);
DISPLAY INVISIBLE (-5275 4425);
FORCEPROP 0 LASTPIN (-5425 4375) $PN 1
J 0
(-5415 4385);
DISPLAY 0.680851 (-5415 4385);
PAINT MONO (-5415 4385);
FORCEPROP 0 LASTPIN (-5575 4375) $PN 2
J 2
(-5585 4385);
DISPLAY 0.680851 (-5585 4385);
PAINT MONO (-5585 4385);
FORCEPROP 2 LAST VALUE DIFF BUS_0.22UF
J 2
(-5625 4375);
DISPLAY 0.553191 (-5625 4375);
FORCEPROP 0 LAST PACK_TYPE C0201
J 2
(-5650 4375);
DISPLAY 0.680851 (-5650 4375);
DISPLAY INVISIBLE (-5650 4375);
FORCEPROP 1 LAST PIN_NAMES_ROTATE True
J 2
(-5500 4375);
DISPLAY 0.489362 (-5500 4375);
PAINT GREEN (-5500 4375);
DISPLAY INVISIBLE (-5500 4375);
FORCEPROP 1 LAST MATERIAL X6S
J 2
(-5350 4425);
DISPLAY 0.723404 (-5350 4425);
PAINT GREEN (-5350 4425);
DISPLAY INVISIBLE (-5350 4425);
FORCEPROP 1 LAST PART_NUMBER SP_CH4221MEE01
J 2
(-5475 4450);
DISPLAY 0.723404 (-5475 4450);
PAINT GREEN (-5475 4450);
DISPLAY INVISIBLE (-5475 4450);
FORCEPROP 0 LAST TOLERANCE 20%
J 2
(-5575 4500);
DISPLAY 0.680851 (-5575 4500);
DISPLAY INVISIBLE (-5575 4500);
FORCEPROP 0 LAST VOLTAGE 6.3V
J 2
(-5575 4550);
DISPLAY 0.680851 (-5575 4550);
DISPLAY INVISIBLE (-5575 4550);
FORCEPROP 1 LAST CDS_LMAN_SYM_OUTLINE -25,50,25,-50
J 2
(-5500 4375);
DISPLAY 0.468085 (-5500 4375);
PAINT GREEN (-5500 4375);
DISPLAY INVISIBLE (-5500 4375);
FORCEPROP 1 LAST PATH I128
J 2
(-5500 4375);
DISPLAY 0.723404 (-5500 4375);
DISPLAY INVISIBLE (-5500 4375);
FORCEPROP 2 LAST CDS_LIB pure_quanta
J 0
(-5500 4375);
DISPLAY INVISIBLE (-5500 4375);
FORCEADD Q_CAP_DIFFBUS..2
R 2
(-5500 4325);
FORCEPROP 1 LAST LOCATION C489
J 2
(-5275 4325);
DISPLAY 0.723404 (-5275 4325);
PAINT GREEN (-5275 4325);
FORCEPROP 0 LAST $SEC 1
J 0
(-5275 4375);
DISPLAY 0.680851 (-5275 4375);
PAINT MONO (-5275 4375);
DISPLAY INVISIBLE (-5275 4375);
FORCEPROP 0 LAST CDS_SEC 1
J 0
(-5275 4375);
DISPLAY 0.680851 (-5275 4375);
DISPLAY INVISIBLE (-5275 4375);
FORCEPROP 0 LASTPIN (-5425 4325) $PN 1
J 0
(-5415 4335);
DISPLAY 0.680851 (-5415 4335);
PAINT MONO (-5415 4335);
FORCEPROP 0 LASTPIN (-5575 4325) $PN 2
J 2
(-5585 4335);
DISPLAY 0.680851 (-5585 4335);
PAINT MONO (-5585 4335);
FORCEPROP 2 LAST VALUE DIFF BUS_0.22UF
J 2
(-5625 4325);
DISPLAY 0.553191 (-5625 4325);
FORCEPROP 2 LAST CDS_LIB pure_quanta
J 0
(-5500 4325);
DISPLAY INVISIBLE (-5500 4325);
FORCEPROP 1 LAST PATH I129
J 2
(-5500 4325);
DISPLAY 0.723404 (-5500 4325);
DISPLAY INVISIBLE (-5500 4325);
FORCEPROP 1 LAST CDS_LMAN_SYM_OUTLINE -25,50,25,-50
J 2
(-5500 4325);
DISPLAY 0.468085 (-5500 4325);
PAINT GREEN (-5500 4325);
DISPLAY INVISIBLE (-5500 4325);
FORCEPROP 0 LAST VOLTAGE 6.3V
J 2
(-5575 4500);
DISPLAY 0.680851 (-5575 4500);
DISPLAY INVISIBLE (-5575 4500);
FORCEPROP 0 LAST TOLERANCE 20%
J 2
(-5575 4450);
DISPLAY 0.680851 (-5575 4450);
DISPLAY INVISIBLE (-5575 4450);
FORCEPROP 1 LAST PART_NUMBER SP_CH4221MEE01
J 2
(-5475 4400);
DISPLAY 0.723404 (-5475 4400);
PAINT GREEN (-5475 4400);
DISPLAY INVISIBLE (-5475 4400);
FORCEPROP 1 LAST MATERIAL X6S
J 2
(-5350 4375);
DISPLAY 0.723404 (-5350 4375);
PAINT GREEN (-5350 4375);
DISPLAY INVISIBLE (-5350 4375);
FORCEPROP 1 LAST PIN_NAMES_ROTATE True
J 2
(-5500 4325);
DISPLAY 0.489362 (-5500 4325);
PAINT GREEN (-5500 4325);
DISPLAY INVISIBLE (-5500 4325);
FORCEPROP 0 LAST PACK_TYPE C0201
J 2
(-5650 4325);
DISPLAY 0.680851 (-5650 4325);
DISPLAY INVISIBLE (-5650 4325);
FORCEADD TAP..6
(-6225 4425);
FORCEPROP 3 LASTPIN (-6175 4425) SIG_NAME P5E_CPU0_G3_TX_DP<13>
J 0
(-6165 4435);
DISPLAY 0.659574 (-6165 4435);
PAINT MONO (-6165 4435);
DISPLAY INVISIBLE (-6165 4435);
FORCEPROP 1 LASTPIN (-6175 4425) BN 13
J 0
(-6227 4433);
DISPLAY 0.680851 (-6227 4433);
PAINT MONO (-6227 4433);
FORCEPROP 2 LAST CDS_LIB standard
J 0
(-6225 4425);
DISPLAY INVISIBLE (-6225 4425);
FORCEPROP 1 LAST PATH I13
J 0
(-6227 4425);
DISPLAY 0.872340 (-6227 4425);
PAINT GREEN (-6227 4425);
DISPLAY INVISIBLE (-6227 4425);
FORCEPROP 1 LAST HDL_TAP TRUE
J 0
(-5900 4300);
DISPLAY 0.574468 (-5900 4300);
PAINT GREEN (-5900 4300);
DISPLAY INVISIBLE (-5900 4300);
FORCEPROP 1 LAST BODY_TYPE PLUMBING
J 0
(-6225 4375);
DISPLAY 0.574468 (-6225 4375);
PAINT GREEN (-6225 4375);
DISPLAY INVISIBLE (-6225 4375);
FORCEADD Q_CAP_DIFFBUS..2
R 2
(-5500 4275);
FORCEPROP 1 LAST LOCATION C490
J 2
(-5275 4275);
DISPLAY 0.723404 (-5275 4275);
PAINT GREEN (-5275 4275);
FORCEPROP 0 LAST $SEC 1
J 0
(-5275 4325);
DISPLAY 0.680851 (-5275 4325);
PAINT MONO (-5275 4325);
DISPLAY INVISIBLE (-5275 4325);
FORCEPROP 0 LAST CDS_SEC 1
J 0
(-5275 4325);
DISPLAY 0.680851 (-5275 4325);
DISPLAY INVISIBLE (-5275 4325);
FORCEPROP 0 LASTPIN (-5425 4275) $PN 1
J 0
(-5415 4285);
DISPLAY 0.680851 (-5415 4285);
PAINT MONO (-5415 4285);
FORCEPROP 0 LASTPIN (-5575 4275) $PN 2
J 2
(-5585 4285);
DISPLAY 0.680851 (-5585 4285);
PAINT MONO (-5585 4285);
FORCEPROP 2 LAST VALUE DIFF BUS_0.22UF
J 2
(-5625 4275);
DISPLAY 0.553191 (-5625 4275);
FORCEPROP 2 LAST CDS_LIB pure_quanta
J 0
(-5500 4275);
DISPLAY INVISIBLE (-5500 4275);
FORCEPROP 1 LAST PATH I130
J 2
(-5500 4275);
DISPLAY 0.723404 (-5500 4275);
DISPLAY INVISIBLE (-5500 4275);
FORCEPROP 1 LAST CDS_LMAN_SYM_OUTLINE -25,50,25,-50
J 2
(-5500 4275);
DISPLAY 0.468085 (-5500 4275);
PAINT GREEN (-5500 4275);
DISPLAY INVISIBLE (-5500 4275);
FORCEPROP 0 LAST VOLTAGE 6.3V
J 2
(-5575 4450);
DISPLAY 0.680851 (-5575 4450);
DISPLAY INVISIBLE (-5575 4450);
FORCEPROP 0 LAST TOLERANCE 20%
J 2
(-5575 4400);
DISPLAY 0.680851 (-5575 4400);
DISPLAY INVISIBLE (-5575 4400);
FORCEPROP 1 LAST PART_NUMBER SP_CH4221MEE01
J 2
(-5475 4350);
DISPLAY 0.723404 (-5475 4350);
PAINT GREEN (-5475 4350);
DISPLAY INVISIBLE (-5475 4350);
FORCEPROP 1 LAST MATERIAL X6S
J 2
(-5350 4325);
DISPLAY 0.723404 (-5350 4325);
PAINT GREEN (-5350 4325);
DISPLAY INVISIBLE (-5350 4325);
FORCEPROP 1 LAST PIN_NAMES_ROTATE True
J 2
(-5500 4275);
DISPLAY 0.489362 (-5500 4275);
PAINT GREEN (-5500 4275);
DISPLAY INVISIBLE (-5500 4275);
FORCEPROP 0 LAST PACK_TYPE C0201
J 2
(-5650 4275);
DISPLAY 0.680851 (-5650 4275);
DISPLAY INVISIBLE (-5650 4275);
FORCEADD Q_CAP_DIFFBUS..2
R 2
(-5500 4225);
FORCEPROP 1 LAST LOCATION C491
J 2
(-5250 4225);
DISPLAY 0.723404 (-5250 4225);
PAINT GREEN (-5250 4225);
FORCEPROP 0 LAST $SEC 1
J 0
(-5250 4275);
DISPLAY 0.680851 (-5250 4275);
PAINT MONO (-5250 4275);
DISPLAY INVISIBLE (-5250 4275);
FORCEPROP 0 LAST CDS_SEC 1
J 0
(-5250 4275);
DISPLAY 0.680851 (-5250 4275);
DISPLAY INVISIBLE (-5250 4275);
FORCEPROP 0 LASTPIN (-5425 4225) $PN 1
J 0
(-5415 4235);
DISPLAY 0.680851 (-5415 4235);
PAINT MONO (-5415 4235);
FORCEPROP 0 LASTPIN (-5575 4225) $PN 2
J 2
(-5585 4235);
DISPLAY 0.680851 (-5585 4235);
PAINT MONO (-5585 4235);
FORCEPROP 2 LAST VALUE DIFF BUS_0.22UF
J 2
(-5625 4225);
DISPLAY 0.553191 (-5625 4225);
FORCEPROP 2 LAST CDS_LIB pure_quanta
J 0
(-5500 4225);
DISPLAY INVISIBLE (-5500 4225);
FORCEPROP 1 LAST PATH I131
J 2
(-5500 4225);
DISPLAY 0.723404 (-5500 4225);
DISPLAY INVISIBLE (-5500 4225);
FORCEPROP 1 LAST CDS_LMAN_SYM_OUTLINE -25,50,25,-50
J 2
(-5500 4225);
DISPLAY 0.468085 (-5500 4225);
PAINT GREEN (-5500 4225);
DISPLAY INVISIBLE (-5500 4225);
FORCEPROP 0 LAST VOLTAGE 6.3V
J 2
(-5575 4400);
DISPLAY 0.680851 (-5575 4400);
DISPLAY INVISIBLE (-5575 4400);
FORCEPROP 0 LAST TOLERANCE 20%
J 2
(-5575 4350);
DISPLAY 0.680851 (-5575 4350);
DISPLAY INVISIBLE (-5575 4350);
FORCEPROP 1 LAST PART_NUMBER SP_CH4221MEE01
J 2
(-5475 4300);
DISPLAY 0.723404 (-5475 4300);
PAINT GREEN (-5475 4300);
DISPLAY INVISIBLE (-5475 4300);
FORCEPROP 1 LAST MATERIAL X6S
J 2
(-5350 4275);
DISPLAY 0.723404 (-5350 4275);
PAINT GREEN (-5350 4275);
DISPLAY INVISIBLE (-5350 4275);
FORCEPROP 1 LAST PIN_NAMES_ROTATE True
J 2
(-5500 4225);
DISPLAY 0.489362 (-5500 4225);
PAINT GREEN (-5500 4225);
DISPLAY INVISIBLE (-5500 4225);
FORCEPROP 0 LAST PACK_TYPE C0201
J 2
(-5650 4225);
DISPLAY 0.680851 (-5650 4225);
DISPLAY INVISIBLE (-5650 4225);
FORCEADD Q_CAP_DIFFBUS..2
R 2
(-5500 4175);
FORCEPROP 1 LAST LOCATION C492
J 2
(-5275 4175);
DISPLAY 0.723404 (-5275 4175);
PAINT GREEN (-5275 4175);
FORCEPROP 0 LAST $SEC 1
J 0
(-5275 4225);
DISPLAY 0.680851 (-5275 4225);
PAINT MONO (-5275 4225);
DISPLAY INVISIBLE (-5275 4225);
FORCEPROP 0 LAST CDS_SEC 1
J 0
(-5275 4225);
DISPLAY 0.680851 (-5275 4225);
DISPLAY INVISIBLE (-5275 4225);
FORCEPROP 0 LASTPIN (-5425 4175) $PN 1
J 0
(-5415 4185);
DISPLAY 0.680851 (-5415 4185);
PAINT MONO (-5415 4185);
FORCEPROP 0 LASTPIN (-5575 4175) $PN 2
J 2
(-5585 4185);
DISPLAY 0.680851 (-5585 4185);
PAINT MONO (-5585 4185);
FORCEPROP 2 LAST VALUE DIFF BUS_0.22UF
J 2
(-5625 4175);
DISPLAY 0.553191 (-5625 4175);
FORCEPROP 2 LAST CDS_LIB pure_quanta
J 0
(-5500 4175);
DISPLAY INVISIBLE (-5500 4175);
FORCEPROP 1 LAST PATH I132
J 2
(-5500 4175);
DISPLAY 0.723404 (-5500 4175);
DISPLAY INVISIBLE (-5500 4175);
FORCEPROP 1 LAST CDS_LMAN_SYM_OUTLINE -25,50,25,-50
J 2
(-5500 4175);
DISPLAY 0.468085 (-5500 4175);
PAINT GREEN (-5500 4175);
DISPLAY INVISIBLE (-5500 4175);
FORCEPROP 0 LAST VOLTAGE 6.3V
J 2
(-5575 4350);
DISPLAY 0.680851 (-5575 4350);
DISPLAY INVISIBLE (-5575 4350);
FORCEPROP 0 LAST TOLERANCE 20%
J 2
(-5575 4300);
DISPLAY 0.680851 (-5575 4300);
DISPLAY INVISIBLE (-5575 4300);
FORCEPROP 1 LAST PART_NUMBER SP_CH4221MEE01
J 2
(-5475 4250);
DISPLAY 0.723404 (-5475 4250);
PAINT GREEN (-5475 4250);
DISPLAY INVISIBLE (-5475 4250);
FORCEPROP 1 LAST MATERIAL X6S
J 2
(-5350 4225);
DISPLAY 0.723404 (-5350 4225);
PAINT GREEN (-5350 4225);
DISPLAY INVISIBLE (-5350 4225);
FORCEPROP 1 LAST PIN_NAMES_ROTATE True
J 2
(-5500 4175);
DISPLAY 0.489362 (-5500 4175);
PAINT GREEN (-5500 4175);
DISPLAY INVISIBLE (-5500 4175);
FORCEPROP 0 LAST PACK_TYPE C0201
J 2
(-5650 4175);
DISPLAY 0.680851 (-5650 4175);
DISPLAY INVISIBLE (-5650 4175);
FORCEADD TAP..6
(-6375 4575);
FORCEPROP 3 LASTPIN (-6325 4575) SIG_NAME P5E_CPU0_G3_TX_DN<11>
J 0
(-6315 4585);
DISPLAY 0.659574 (-6315 4585);
PAINT MONO (-6315 4585);
DISPLAY INVISIBLE (-6315 4585);
FORCEPROP 1 LASTPIN (-6325 4575) BN 11
J 0
(-6377 4583);
DISPLAY 0.680851 (-6377 4583);
PAINT MONO (-6377 4583);
FORCEPROP 2 LAST CDS_LIB standard
J 0
(-6375 4575);
DISPLAY INVISIBLE (-6375 4575);
FORCEPROP 1 LAST PATH I14
J 0
(-6377 4575);
DISPLAY 0.872340 (-6377 4575);
PAINT GREEN (-6377 4575);
DISPLAY INVISIBLE (-6377 4575);
FORCEPROP 1 LAST HDL_TAP TRUE
J 0
(-6050 4450);
DISPLAY 0.574468 (-6050 4450);
PAINT GREEN (-6050 4450);
DISPLAY INVISIBLE (-6050 4450);
FORCEPROP 1 LAST BODY_TYPE PLUMBING
J 0
(-6375 4525);
DISPLAY 0.574468 (-6375 4525);
PAINT GREEN (-6375 4525);
DISPLAY INVISIBLE (-6375 4525);
FORCEADD TAP..6
(-6375 4675);
FORCEPROP 3 LASTPIN (-6325 4675) SIG_NAME P5E_CPU0_G3_TX_DN<10>
J 0
(-6315 4685);
DISPLAY 0.659574 (-6315 4685);
PAINT MONO (-6315 4685);
DISPLAY INVISIBLE (-6315 4685);
FORCEPROP 1 LASTPIN (-6325 4675) BN 10
J 0
(-6377 4683);
DISPLAY 0.680851 (-6377 4683);
PAINT MONO (-6377 4683);
FORCEPROP 2 LAST CDS_LIB standard
J 0
(-6375 4675);
DISPLAY INVISIBLE (-6375 4675);
FORCEPROP 1 LAST PATH I15
J 0
(-6377 4675);
DISPLAY 0.872340 (-6377 4675);
PAINT GREEN (-6377 4675);
DISPLAY INVISIBLE (-6377 4675);
FORCEPROP 1 LAST HDL_TAP TRUE
J 0
(-6050 4550);
DISPLAY 0.574468 (-6050 4550);
PAINT GREEN (-6050 4550);
DISPLAY INVISIBLE (-6050 4550);
FORCEPROP 1 LAST BODY_TYPE PLUMBING
J 0
(-6375 4625);
DISPLAY 0.574468 (-6375 4625);
PAINT GREEN (-6375 4625);
DISPLAY INVISIBLE (-6375 4625);
FORCEADD TAP..6
(-6225 4625);
FORCEPROP 3 LASTPIN (-6175 4625) SIG_NAME P5E_CPU0_G3_TX_DP<11>
J 0
(-6165 4635);
DISPLAY 0.659574 (-6165 4635);
PAINT MONO (-6165 4635);
DISPLAY INVISIBLE (-6165 4635);
FORCEPROP 1 LASTPIN (-6175 4625) BN 11
J 0
(-6227 4633);
DISPLAY 0.680851 (-6227 4633);
PAINT MONO (-6227 4633);
FORCEPROP 2 LAST CDS_LIB standard
J 0
(-6225 4625);
DISPLAY INVISIBLE (-6225 4625);
FORCEPROP 1 LAST PATH I16
J 0
(-6227 4625);
DISPLAY 0.872340 (-6227 4625);
PAINT GREEN (-6227 4625);
DISPLAY INVISIBLE (-6227 4625);
FORCEPROP 1 LAST HDL_TAP TRUE
J 0
(-5900 4500);
DISPLAY 0.574468 (-5900 4500);
PAINT GREEN (-5900 4500);
DISPLAY INVISIBLE (-5900 4500);
FORCEPROP 1 LAST BODY_TYPE PLUMBING
J 0
(-6225 4575);
DISPLAY 0.574468 (-6225 4575);
PAINT GREEN (-6225 4575);
DISPLAY INVISIBLE (-6225 4575);
FORCEADD TAP..6
(-6225 4525);
FORCEPROP 3 LASTPIN (-6175 4525) SIG_NAME P5E_CPU0_G3_TX_DP<12>
J 0
(-6165 4535);
DISPLAY 0.659574 (-6165 4535);
PAINT MONO (-6165 4535);
DISPLAY INVISIBLE (-6165 4535);
FORCEPROP 1 LASTPIN (-6175 4525) BN 12
J 0
(-6227 4533);
DISPLAY 0.680851 (-6227 4533);
PAINT MONO (-6227 4533);
FORCEPROP 2 LAST CDS_LIB standard
J 0
(-6225 4525);
DISPLAY INVISIBLE (-6225 4525);
FORCEPROP 1 LAST PATH I17
J 0
(-6227 4525);
DISPLAY 0.872340 (-6227 4525);
PAINT GREEN (-6227 4525);
DISPLAY INVISIBLE (-6227 4525);
FORCEPROP 1 LAST HDL_TAP TRUE
J 0
(-5900 4400);
DISPLAY 0.574468 (-5900 4400);
PAINT GREEN (-5900 4400);
DISPLAY INVISIBLE (-5900 4400);
FORCEPROP 1 LAST BODY_TYPE PLUMBING
J 0
(-6225 4475);
DISPLAY 0.574468 (-6225 4475);
PAINT GREEN (-6225 4475);
DISPLAY INVISIBLE (-6225 4475);
FORCEADD TAP..6
(-6225 4725);
FORCEPROP 3 LASTPIN (-6175 4725) SIG_NAME P5E_CPU0_G3_TX_DP<10>
J 0
(-6165 4735);
DISPLAY 0.659574 (-6165 4735);
PAINT MONO (-6165 4735);
DISPLAY INVISIBLE (-6165 4735);
FORCEPROP 1 LASTPIN (-6175 4725) BN 10
J 0
(-6227 4733);
DISPLAY 0.680851 (-6227 4733);
PAINT MONO (-6227 4733);
FORCEPROP 2 LAST CDS_LIB standard
J 0
(-6225 4725);
DISPLAY INVISIBLE (-6225 4725);
FORCEPROP 1 LAST PATH I18
J 0
(-6227 4725);
DISPLAY 0.872340 (-6227 4725);
PAINT GREEN (-6227 4725);
DISPLAY INVISIBLE (-6227 4725);
FORCEPROP 1 LAST HDL_TAP TRUE
J 0
(-5900 4600);
DISPLAY 0.574468 (-5900 4600);
PAINT GREEN (-5900 4600);
DISPLAY INVISIBLE (-5900 4600);
FORCEPROP 1 LAST BODY_TYPE PLUMBING
J 0
(-6225 4675);
DISPLAY 0.574468 (-6225 4675);
PAINT GREEN (-6225 4675);
DISPLAY INVISIBLE (-6225 4675);
FORCEADD TAP..6
(-6375 4775);
FORCEPROP 3 LASTPIN (-6325 4775) SIG_NAME P5E_CPU0_G3_TX_DN<9>
J 0
(-6315 4785);
DISPLAY 0.659574 (-6315 4785);
PAINT MONO (-6315 4785);
DISPLAY INVISIBLE (-6315 4785);
FORCEPROP 1 LASTPIN (-6325 4775) BN 9
J 0
(-6377 4783);
DISPLAY 0.680851 (-6377 4783);
PAINT MONO (-6377 4783);
FORCEPROP 2 LAST CDS_LIB standard
J 0
(-6375 4775);
DISPLAY INVISIBLE (-6375 4775);
FORCEPROP 1 LAST PATH I19
J 0
(-6377 4775);
DISPLAY 0.872340 (-6377 4775);
PAINT GREEN (-6377 4775);
DISPLAY INVISIBLE (-6377 4775);
FORCEPROP 1 LAST HDL_TAP TRUE
J 0
(-6050 4650);
DISPLAY 0.574468 (-6050 4650);
PAINT GREEN (-6050 4650);
DISPLAY INVISIBLE (-6050 4650);
FORCEPROP 1 LAST BODY_TYPE PLUMBING
J 0
(-6375 4725);
DISPLAY 0.574468 (-6375 4725);
PAINT GREEN (-6375 4725);
DISPLAY INVISIBLE (-6375 4725);
FORCEADD TAP..6
(-6225 4225);
FORCEPROP 3 LASTPIN (-6175 4225) SIG_NAME P5E_CPU0_G3_TX_DP<15>
J 0
(-6165 4235);
DISPLAY 0.659574 (-6165 4235);
PAINT MONO (-6165 4235);
DISPLAY INVISIBLE (-6165 4235);
FORCEPROP 1 LASTPIN (-6175 4225) BN 15
J 0
(-6227 4233);
DISPLAY 0.680851 (-6227 4233);
PAINT MONO (-6227 4233);
FORCEPROP 2 LAST CDS_LIB standard
J 0
(-6225 4225);
DISPLAY INVISIBLE (-6225 4225);
FORCEPROP 1 LAST PATH I2
J 0
(-6227 4225);
DISPLAY 0.872340 (-6227 4225);
PAINT GREEN (-6227 4225);
DISPLAY INVISIBLE (-6227 4225);
FORCEPROP 1 LAST HDL_TAP TRUE
J 0
(-5900 4100);
DISPLAY 0.574468 (-5900 4100);
PAINT GREEN (-5900 4100);
DISPLAY INVISIBLE (-5900 4100);
FORCEPROP 1 LAST BODY_TYPE PLUMBING
J 0
(-6225 4175);
DISPLAY 0.574468 (-6225 4175);
PAINT GREEN (-6225 4175);
DISPLAY INVISIBLE (-6225 4175);
FORCEADD TAP..6
(-6375 4875);
FORCEPROP 3 LASTPIN (-6325 4875) SIG_NAME P5E_CPU0_G3_TX_DN<8>
J 0
(-6315 4885);
DISPLAY 0.659574 (-6315 4885);
PAINT MONO (-6315 4885);
DISPLAY INVISIBLE (-6315 4885);
FORCEPROP 1 LASTPIN (-6325 4875) BN 8
J 0
(-6377 4883);
DISPLAY 0.680851 (-6377 4883);
PAINT MONO (-6377 4883);
FORCEPROP 2 LAST CDS_LIB standard
J 0
(-6375 4875);
DISPLAY INVISIBLE (-6375 4875);
FORCEPROP 1 LAST PATH I20
J 0
(-6377 4875);
DISPLAY 0.872340 (-6377 4875);
PAINT GREEN (-6377 4875);
DISPLAY INVISIBLE (-6377 4875);
FORCEPROP 1 LAST HDL_TAP TRUE
J 0
(-6050 4750);
DISPLAY 0.574468 (-6050 4750);
PAINT GREEN (-6050 4750);
DISPLAY INVISIBLE (-6050 4750);
FORCEPROP 1 LAST BODY_TYPE PLUMBING
J 0
(-6375 4825);
DISPLAY 0.574468 (-6375 4825);
PAINT GREEN (-6375 4825);
DISPLAY INVISIBLE (-6375 4825);
FORCEADD TAP..6
(-6375 4975);
FORCEPROP 3 LASTPIN (-6325 4975) SIG_NAME P5E_CPU0_G3_TX_DN<7>
J 0
(-6315 4985);
DISPLAY 0.659574 (-6315 4985);
PAINT MONO (-6315 4985);
DISPLAY INVISIBLE (-6315 4985);
FORCEPROP 1 LASTPIN (-6325 4975) BN 7
J 0
(-6377 4983);
DISPLAY 0.680851 (-6377 4983);
PAINT MONO (-6377 4983);
FORCEPROP 2 LAST CDS_LIB standard
J 0
(-6375 4975);
DISPLAY INVISIBLE (-6375 4975);
FORCEPROP 1 LAST PATH I21
J 0
(-6377 4975);
DISPLAY 0.872340 (-6377 4975);
PAINT GREEN (-6377 4975);
DISPLAY INVISIBLE (-6377 4975);
FORCEPROP 1 LAST HDL_TAP TRUE
J 0
(-6050 4850);
DISPLAY 0.574468 (-6050 4850);
PAINT GREEN (-6050 4850);
DISPLAY INVISIBLE (-6050 4850);
FORCEPROP 1 LAST BODY_TYPE PLUMBING
J 0
(-6375 4925);
DISPLAY 0.574468 (-6375 4925);
PAINT GREEN (-6375 4925);
DISPLAY INVISIBLE (-6375 4925);
FORCEADD TAP..6
(-6225 4825);
FORCEPROP 3 LASTPIN (-6175 4825) SIG_NAME P5E_CPU0_G3_TX_DP<9>
J 0
(-6165 4835);
DISPLAY 0.659574 (-6165 4835);
PAINT MONO (-6165 4835);
DISPLAY INVISIBLE (-6165 4835);
FORCEPROP 1 LASTPIN (-6175 4825) BN 9
J 0
(-6227 4833);
DISPLAY 0.680851 (-6227 4833);
PAINT MONO (-6227 4833);
FORCEPROP 2 LAST CDS_LIB standard
J 0
(-6225 4825);
DISPLAY INVISIBLE (-6225 4825);
FORCEPROP 1 LAST PATH I22
J 0
(-6227 4825);
DISPLAY 0.872340 (-6227 4825);
PAINT GREEN (-6227 4825);
DISPLAY INVISIBLE (-6227 4825);
FORCEPROP 1 LAST HDL_TAP TRUE
J 0
(-5900 4700);
DISPLAY 0.574468 (-5900 4700);
PAINT GREEN (-5900 4700);
DISPLAY INVISIBLE (-5900 4700);
FORCEPROP 1 LAST BODY_TYPE PLUMBING
J 0
(-6225 4775);
DISPLAY 0.574468 (-6225 4775);
PAINT GREEN (-6225 4775);
DISPLAY INVISIBLE (-6225 4775);
FORCEADD TAP..6
(-6225 4925);
FORCEPROP 3 LASTPIN (-6175 4925) SIG_NAME P5E_CPU0_G3_TX_DP<8>
J 0
(-6165 4935);
DISPLAY 0.659574 (-6165 4935);
PAINT MONO (-6165 4935);
DISPLAY INVISIBLE (-6165 4935);
FORCEPROP 1 LASTPIN (-6175 4925) BN 8
J 0
(-6227 4933);
DISPLAY 0.680851 (-6227 4933);
PAINT MONO (-6227 4933);
FORCEPROP 2 LAST CDS_LIB standard
J 0
(-6225 4925);
DISPLAY INVISIBLE (-6225 4925);
FORCEPROP 1 LAST PATH I23
J 0
(-6227 4925);
DISPLAY 0.872340 (-6227 4925);
PAINT GREEN (-6227 4925);
DISPLAY INVISIBLE (-6227 4925);
FORCEPROP 1 LAST HDL_TAP TRUE
J 0
(-5900 4800);
DISPLAY 0.574468 (-5900 4800);
PAINT GREEN (-5900 4800);
DISPLAY INVISIBLE (-5900 4800);
FORCEPROP 1 LAST BODY_TYPE PLUMBING
J 0
(-6225 4875);
DISPLAY 0.574468 (-6225 4875);
PAINT GREEN (-6225 4875);
DISPLAY INVISIBLE (-6225 4875);
FORCEADD TAP..6
(-6375 5075);
FORCEPROP 3 LASTPIN (-6325 5075) SIG_NAME P5E_CPU0_G3_TX_DN<6>
J 0
(-6315 5085);
DISPLAY 0.659574 (-6315 5085);
PAINT MONO (-6315 5085);
DISPLAY INVISIBLE (-6315 5085);
FORCEPROP 1 LASTPIN (-6325 5075) BN 6
J 0
(-6377 5083);
DISPLAY 0.680851 (-6377 5083);
PAINT MONO (-6377 5083);
FORCEPROP 2 LAST CDS_LIB standard
J 0
(-6375 5075);
DISPLAY INVISIBLE (-6375 5075);
FORCEPROP 1 LAST PATH I24
J 0
(-6377 5075);
DISPLAY 0.872340 (-6377 5075);
PAINT GREEN (-6377 5075);
DISPLAY INVISIBLE (-6377 5075);
FORCEPROP 1 LAST HDL_TAP TRUE
J 0
(-6050 4950);
DISPLAY 0.574468 (-6050 4950);
PAINT GREEN (-6050 4950);
DISPLAY INVISIBLE (-6050 4950);
FORCEPROP 1 LAST BODY_TYPE PLUMBING
J 0
(-6375 5025);
DISPLAY 0.574468 (-6375 5025);
PAINT GREEN (-6375 5025);
DISPLAY INVISIBLE (-6375 5025);
FORCEADD TAP..6
(-6375 5175);
FORCEPROP 3 LASTPIN (-6325 5175) SIG_NAME P5E_CPU0_G3_TX_DN<5>
J 0
(-6315 5185);
DISPLAY 0.659574 (-6315 5185);
PAINT MONO (-6315 5185);
DISPLAY INVISIBLE (-6315 5185);
FORCEPROP 1 LASTPIN (-6325 5175) BN 5
J 0
(-6377 5183);
DISPLAY 0.680851 (-6377 5183);
PAINT MONO (-6377 5183);
FORCEPROP 2 LAST CDS_LIB standard
J 0
(-6375 5175);
DISPLAY INVISIBLE (-6375 5175);
FORCEPROP 1 LAST PATH I25
J 0
(-6377 5175);
DISPLAY 0.872340 (-6377 5175);
PAINT GREEN (-6377 5175);
DISPLAY INVISIBLE (-6377 5175);
FORCEPROP 1 LAST HDL_TAP TRUE
J 0
(-6050 5050);
DISPLAY 0.574468 (-6050 5050);
PAINT GREEN (-6050 5050);
DISPLAY INVISIBLE (-6050 5050);
FORCEPROP 1 LAST BODY_TYPE PLUMBING
J 0
(-6375 5125);
DISPLAY 0.574468 (-6375 5125);
PAINT GREEN (-6375 5125);
DISPLAY INVISIBLE (-6375 5125);
FORCEADD TAP..6
(-6225 5125);
FORCEPROP 3 LASTPIN (-6175 5125) SIG_NAME P5E_CPU0_G3_TX_DP<6>
J 0
(-6165 5135);
DISPLAY 0.659574 (-6165 5135);
PAINT MONO (-6165 5135);
DISPLAY INVISIBLE (-6165 5135);
FORCEPROP 1 LASTPIN (-6175 5125) BN 6
J 0
(-6227 5133);
DISPLAY 0.680851 (-6227 5133);
PAINT MONO (-6227 5133);
FORCEPROP 2 LAST CDS_LIB standard
J 0
(-6225 5125);
DISPLAY INVISIBLE (-6225 5125);
FORCEPROP 1 LAST PATH I26
J 0
(-6227 5125);
DISPLAY 0.872340 (-6227 5125);
PAINT GREEN (-6227 5125);
DISPLAY INVISIBLE (-6227 5125);
FORCEPROP 1 LAST HDL_TAP TRUE
J 0
(-5900 5000);
DISPLAY 0.574468 (-5900 5000);
PAINT GREEN (-5900 5000);
DISPLAY INVISIBLE (-5900 5000);
FORCEPROP 1 LAST BODY_TYPE PLUMBING
J 0
(-6225 5075);
DISPLAY 0.574468 (-6225 5075);
PAINT GREEN (-6225 5075);
DISPLAY INVISIBLE (-6225 5075);
FORCEADD TAP..6
(-6225 5025);
FORCEPROP 3 LASTPIN (-6175 5025) SIG_NAME P5E_CPU0_G3_TX_DP<7>
J 0
(-6165 5035);
DISPLAY 0.659574 (-6165 5035);
PAINT MONO (-6165 5035);
DISPLAY INVISIBLE (-6165 5035);
FORCEPROP 1 LASTPIN (-6175 5025) BN 7
J 0
(-6227 5033);
DISPLAY 0.680851 (-6227 5033);
PAINT MONO (-6227 5033);
FORCEPROP 2 LAST CDS_LIB standard
J 0
(-6225 5025);
DISPLAY INVISIBLE (-6225 5025);
FORCEPROP 1 LAST PATH I27
J 0
(-6227 5025);
DISPLAY 0.872340 (-6227 5025);
PAINT GREEN (-6227 5025);
DISPLAY INVISIBLE (-6227 5025);
FORCEPROP 1 LAST HDL_TAP TRUE
J 0
(-5900 4900);
DISPLAY 0.574468 (-5900 4900);
PAINT GREEN (-5900 4900);
DISPLAY INVISIBLE (-5900 4900);
FORCEPROP 1 LAST BODY_TYPE PLUMBING
J 0
(-6225 4975);
DISPLAY 0.574468 (-6225 4975);
PAINT GREEN (-6225 4975);
DISPLAY INVISIBLE (-6225 4975);
FORCEADD TAP..6
(-6225 5225);
FORCEPROP 3 LASTPIN (-6175 5225) SIG_NAME P5E_CPU0_G3_TX_DP<5>
J 0
(-6165 5235);
DISPLAY 0.659574 (-6165 5235);
PAINT MONO (-6165 5235);
DISPLAY INVISIBLE (-6165 5235);
FORCEPROP 1 LASTPIN (-6175 5225) BN 5
J 0
(-6227 5233);
DISPLAY 0.680851 (-6227 5233);
PAINT MONO (-6227 5233);
FORCEPROP 2 LAST CDS_LIB standard
J 0
(-6225 5225);
DISPLAY INVISIBLE (-6225 5225);
FORCEPROP 1 LAST PATH I28
J 0
(-6227 5225);
DISPLAY 0.872340 (-6227 5225);
PAINT GREEN (-6227 5225);
DISPLAY INVISIBLE (-6227 5225);
FORCEPROP 1 LAST HDL_TAP TRUE
J 0
(-5900 5100);
DISPLAY 0.574468 (-5900 5100);
PAINT GREEN (-5900 5100);
DISPLAY INVISIBLE (-5900 5100);
FORCEPROP 1 LAST BODY_TYPE PLUMBING
J 0
(-6225 5175);
DISPLAY 0.574468 (-6225 5175);
PAINT GREEN (-6225 5175);
DISPLAY INVISIBLE (-6225 5175);
FORCEADD TAP..6
(-6375 5375);
FORCEPROP 3 LASTPIN (-6325 5375) SIG_NAME P5E_CPU0_G3_TX_DN<3>
J 0
(-6315 5385);
DISPLAY 0.659574 (-6315 5385);
PAINT MONO (-6315 5385);
DISPLAY INVISIBLE (-6315 5385);
FORCEPROP 1 LASTPIN (-6325 5375) BN 3
J 0
(-6377 5383);
DISPLAY 0.680851 (-6377 5383);
PAINT MONO (-6377 5383);
FORCEPROP 2 LAST CDS_LIB standard
J 0
(-6375 5375);
DISPLAY INVISIBLE (-6375 5375);
FORCEPROP 1 LAST PATH I49
J 0
(-6377 5375);
DISPLAY 0.872340 (-6377 5375);
PAINT GREEN (-6377 5375);
DISPLAY INVISIBLE (-6377 5375);
FORCEPROP 1 LAST HDL_TAP TRUE
J 0
(-6050 5250);
DISPLAY 0.574468 (-6050 5250);
PAINT GREEN (-6050 5250);
DISPLAY INVISIBLE (-6050 5250);
FORCEPROP 1 LAST BODY_TYPE PLUMBING
J 0
(-6375 5325);
DISPLAY 0.574468 (-6375 5325);
PAINT GREEN (-6375 5325);
DISPLAY INVISIBLE (-6375 5325);
FORCEADD TAP..6
R 2
(-4500 4225);
FORCEPROP 3 LASTPIN (-4550 4225) SIG_NAME P5E_CPU0_G3_TX_C_DP<15>
J 0
(-4540 4235);
DISPLAY 0.659574 (-4540 4235);
PAINT MONO (-4540 4235);
DISPLAY INVISIBLE (-4540 4235);
FORCEPROP 1 LASTPIN (-4550 4225) BN 15
J 2
(-4498 4233);
DISPLAY 0.680851 (-4498 4233);
PAINT MONO (-4498 4233);
FORCEPROP 2 LAST CDS_LIB standard
J 0
(-4500 4225);
DISPLAY INVISIBLE (-4500 4225);
FORCEPROP 1 LAST PATH I5
J 2
(-4498 4225);
DISPLAY 0.872340 (-4498 4225);
PAINT GREEN (-4498 4225);
DISPLAY INVISIBLE (-4498 4225);
FORCEPROP 2 LAST BOM_COST IO_SLOT
J 0
(-5000 4325);
DISPLAY 0.829787 (-5000 4325);
DISPLAY INVISIBLE (-5000 4325);
FORCEPROP 1 LAST BODY_TYPE PLUMBING
J 2
(-4500 4175);
DISPLAY 0.702128 (-4500 4175);
PAINT GREEN (-4500 4175);
DISPLAY INVISIBLE (-4500 4175);
FORCEPROP 1 LAST HDL_TAP TRUE
J 2
(-4825 4100);
DISPLAY 0.702128 (-4825 4100);
PAINT GREEN (-4825 4100);
DISPLAY INVISIBLE (-4825 4100);
FORCEPROP 2 LAST ROOM RISER1
J 0
(-5000 4275);
DISPLAY 0.829787 (-5000 4275);
PAINT RED (-5000 4275);
DISPLAY INVISIBLE (-5000 4275);
FORCEADD TAP..6
(-6375 5275);
FORCEPROP 3 LASTPIN (-6325 5275) SIG_NAME P5E_CPU0_G3_TX_DN<4>
J 0
(-6315 5285);
DISPLAY 0.659574 (-6315 5285);
PAINT MONO (-6315 5285);
DISPLAY INVISIBLE (-6315 5285);
FORCEPROP 1 LASTPIN (-6325 5275) BN 4
J 0
(-6377 5283);
DISPLAY 0.680851 (-6377 5283);
PAINT MONO (-6377 5283);
FORCEPROP 2 LAST CDS_LIB standard
J 0
(-6375 5275);
DISPLAY INVISIBLE (-6375 5275);
FORCEPROP 1 LAST PATH I50
J 0
(-6377 5275);
DISPLAY 0.872340 (-6377 5275);
PAINT GREEN (-6377 5275);
DISPLAY INVISIBLE (-6377 5275);
FORCEPROP 1 LAST HDL_TAP TRUE
J 0
(-6050 5150);
DISPLAY 0.574468 (-6050 5150);
PAINT GREEN (-6050 5150);
DISPLAY INVISIBLE (-6050 5150);
FORCEPROP 1 LAST BODY_TYPE PLUMBING
J 0
(-6375 5225);
DISPLAY 0.574468 (-6375 5225);
PAINT GREEN (-6375 5225);
DISPLAY INVISIBLE (-6375 5225);
FORCEADD TAP..6
(-6375 5475);
FORCEPROP 3 LASTPIN (-6325 5475) SIG_NAME P5E_CPU0_G3_TX_DN<2>
J 0
(-6315 5485);
DISPLAY 0.659574 (-6315 5485);
PAINT MONO (-6315 5485);
DISPLAY INVISIBLE (-6315 5485);
FORCEPROP 1 LASTPIN (-6325 5475) BN 2
J 0
(-6377 5483);
DISPLAY 0.680851 (-6377 5483);
PAINT MONO (-6377 5483);
FORCEPROP 2 LAST CDS_LIB standard
J 0
(-6375 5475);
DISPLAY INVISIBLE (-6375 5475);
FORCEPROP 1 LAST PATH I51
J 0
(-6377 5475);
DISPLAY 0.872340 (-6377 5475);
PAINT GREEN (-6377 5475);
DISPLAY INVISIBLE (-6377 5475);
FORCEPROP 1 LAST HDL_TAP TRUE
J 0
(-6050 5350);
DISPLAY 0.574468 (-6050 5350);
PAINT GREEN (-6050 5350);
DISPLAY INVISIBLE (-6050 5350);
FORCEPROP 1 LAST BODY_TYPE PLUMBING
J 0
(-6375 5425);
DISPLAY 0.574468 (-6375 5425);
PAINT GREEN (-6375 5425);
DISPLAY INVISIBLE (-6375 5425);
FORCEADD TAP..6
(-6225 5325);
FORCEPROP 3 LASTPIN (-6175 5325) SIG_NAME P5E_CPU0_G3_TX_DP<4>
J 0
(-6165 5335);
DISPLAY 0.659574 (-6165 5335);
PAINT MONO (-6165 5335);
DISPLAY INVISIBLE (-6165 5335);
FORCEPROP 1 LASTPIN (-6175 5325) BN 4
J 0
(-6227 5333);
DISPLAY 0.680851 (-6227 5333);
PAINT MONO (-6227 5333);
FORCEPROP 2 LAST CDS_LIB standard
J 0
(-6225 5325);
DISPLAY INVISIBLE (-6225 5325);
FORCEPROP 1 LAST PATH I52
J 0
(-6227 5325);
DISPLAY 0.872340 (-6227 5325);
PAINT GREEN (-6227 5325);
DISPLAY INVISIBLE (-6227 5325);
FORCEPROP 1 LAST HDL_TAP TRUE
J 0
(-5900 5200);
DISPLAY 0.574468 (-5900 5200);
PAINT GREEN (-5900 5200);
DISPLAY INVISIBLE (-5900 5200);
FORCEPROP 1 LAST BODY_TYPE PLUMBING
J 0
(-6225 5275);
DISPLAY 0.574468 (-6225 5275);
PAINT GREEN (-6225 5275);
DISPLAY INVISIBLE (-6225 5275);
FORCEADD TAP..6
(-6225 5525);
FORCEPROP 3 LASTPIN (-6175 5525) SIG_NAME P5E_CPU0_G3_TX_DP<2>
J 0
(-6165 5535);
DISPLAY 0.659574 (-6165 5535);
PAINT MONO (-6165 5535);
DISPLAY INVISIBLE (-6165 5535);
FORCEPROP 1 LASTPIN (-6175 5525) BN 2
J 0
(-6227 5533);
DISPLAY 0.680851 (-6227 5533);
PAINT MONO (-6227 5533);
FORCEPROP 2 LAST CDS_LIB standard
J 0
(-6225 5525);
DISPLAY INVISIBLE (-6225 5525);
FORCEPROP 1 LAST PATH I53
J 0
(-6227 5525);
DISPLAY 0.872340 (-6227 5525);
PAINT GREEN (-6227 5525);
DISPLAY INVISIBLE (-6227 5525);
FORCEPROP 1 LAST HDL_TAP TRUE
J 0
(-5900 5400);
DISPLAY 0.574468 (-5900 5400);
PAINT GREEN (-5900 5400);
DISPLAY INVISIBLE (-5900 5400);
FORCEPROP 1 LAST BODY_TYPE PLUMBING
J 0
(-6225 5475);
DISPLAY 0.574468 (-6225 5475);
PAINT GREEN (-6225 5475);
DISPLAY INVISIBLE (-6225 5475);
FORCEADD TAP..6
(-6225 5425);
FORCEPROP 3 LASTPIN (-6175 5425) SIG_NAME P5E_CPU0_G3_TX_DP<3>
J 0
(-6165 5435);
DISPLAY 0.659574 (-6165 5435);
PAINT MONO (-6165 5435);
DISPLAY INVISIBLE (-6165 5435);
FORCEPROP 1 LASTPIN (-6175 5425) BN 3
J 0
(-6227 5433);
DISPLAY 0.680851 (-6227 5433);
PAINT MONO (-6227 5433);
FORCEPROP 2 LAST CDS_LIB standard
J 0
(-6225 5425);
DISPLAY INVISIBLE (-6225 5425);
FORCEPROP 1 LAST PATH I54
J 0
(-6227 5425);
DISPLAY 0.872340 (-6227 5425);
PAINT GREEN (-6227 5425);
DISPLAY INVISIBLE (-6227 5425);
FORCEPROP 1 LAST HDL_TAP TRUE
J 0
(-5900 5300);
DISPLAY 0.574468 (-5900 5300);
PAINT GREEN (-5900 5300);
DISPLAY INVISIBLE (-5900 5300);
FORCEPROP 1 LAST BODY_TYPE PLUMBING
J 0
(-6225 5375);
DISPLAY 0.574468 (-6225 5375);
PAINT GREEN (-6225 5375);
DISPLAY INVISIBLE (-6225 5375);
FORCEADD TAP..6
(-6375 5575);
FORCEPROP 3 LASTPIN (-6325 5575) SIG_NAME P5E_CPU0_G3_TX_DN<1>
J 0
(-6315 5585);
DISPLAY 0.659574 (-6315 5585);
PAINT MONO (-6315 5585);
DISPLAY INVISIBLE (-6315 5585);
FORCEPROP 1 LASTPIN (-6325 5575) BN 1
J 0
(-6377 5583);
DISPLAY 0.680851 (-6377 5583);
PAINT MONO (-6377 5583);
FORCEPROP 2 LAST CDS_LIB standard
J 0
(-6375 5575);
DISPLAY INVISIBLE (-6375 5575);
FORCEPROP 1 LAST PATH I55
J 0
(-6377 5575);
DISPLAY 0.872340 (-6377 5575);
PAINT GREEN (-6377 5575);
DISPLAY INVISIBLE (-6377 5575);
FORCEPROP 1 LAST HDL_TAP TRUE
J 0
(-6050 5450);
DISPLAY 0.574468 (-6050 5450);
PAINT GREEN (-6050 5450);
DISPLAY INVISIBLE (-6050 5450);
FORCEPROP 1 LAST BODY_TYPE PLUMBING
J 0
(-6375 5525);
DISPLAY 0.574468 (-6375 5525);
PAINT GREEN (-6375 5525);
DISPLAY INVISIBLE (-6375 5525);
FORCEADD TAP..6
(-6375 5675);
FORCEPROP 3 LASTPIN (-6325 5675) SIG_NAME P5E_CPU0_G3_TX_DN<0>
J 0
(-6315 5685);
DISPLAY 0.659574 (-6315 5685);
PAINT MONO (-6315 5685);
DISPLAY INVISIBLE (-6315 5685);
FORCEPROP 1 LASTPIN (-6325 5675) BN 0
J 0
(-6377 5683);
DISPLAY 0.680851 (-6377 5683);
PAINT MONO (-6377 5683);
FORCEPROP 2 LAST CDS_LIB standard
J 0
(-6375 5675);
DISPLAY INVISIBLE (-6375 5675);
FORCEPROP 1 LAST PATH I56
J 0
(-6377 5675);
DISPLAY 0.872340 (-6377 5675);
PAINT GREEN (-6377 5675);
DISPLAY INVISIBLE (-6377 5675);
FORCEPROP 1 LAST HDL_TAP TRUE
J 0
(-6050 5550);
DISPLAY 0.574468 (-6050 5550);
PAINT GREEN (-6050 5550);
DISPLAY INVISIBLE (-6050 5550);
FORCEPROP 1 LAST BODY_TYPE PLUMBING
J 0
(-6375 5625);
DISPLAY 0.574468 (-6375 5625);
PAINT GREEN (-6375 5625);
DISPLAY INVISIBLE (-6375 5625);
FORCEADD TAP..6
(-6225 5625);
FORCEPROP 3 LASTPIN (-6175 5625) SIG_NAME P5E_CPU0_G3_TX_DP<1>
J 0
(-6165 5635);
DISPLAY 0.659574 (-6165 5635);
PAINT MONO (-6165 5635);
DISPLAY INVISIBLE (-6165 5635);
FORCEPROP 1 LASTPIN (-6175 5625) BN 1
J 0
(-6227 5633);
DISPLAY 0.680851 (-6227 5633);
PAINT MONO (-6227 5633);
FORCEPROP 2 LAST CDS_LIB standard
J 0
(-6225 5625);
DISPLAY INVISIBLE (-6225 5625);
FORCEPROP 1 LAST PATH I57
J 0
(-6227 5625);
DISPLAY 0.872340 (-6227 5625);
PAINT GREEN (-6227 5625);
DISPLAY INVISIBLE (-6227 5625);
FORCEPROP 1 LAST HDL_TAP TRUE
J 0
(-5900 5500);
DISPLAY 0.574468 (-5900 5500);
PAINT GREEN (-5900 5500);
DISPLAY INVISIBLE (-5900 5500);
FORCEPROP 1 LAST BODY_TYPE PLUMBING
J 0
(-6225 5575);
DISPLAY 0.574468 (-6225 5575);
PAINT GREEN (-6225 5575);
DISPLAY INVISIBLE (-6225 5575);
FORCEADD TAP..6
(-6225 5725);
FORCEPROP 3 LASTPIN (-6175 5725) SIG_NAME P5E_CPU0_G3_TX_DP<0>
J 0
(-6165 5735);
DISPLAY 0.659574 (-6165 5735);
PAINT MONO (-6165 5735);
DISPLAY INVISIBLE (-6165 5735);
FORCEPROP 1 LASTPIN (-6175 5725) BN 0
J 0
(-6227 5733);
DISPLAY 0.680851 (-6227 5733);
PAINT MONO (-6227 5733);
FORCEPROP 2 LAST CDS_LIB standard
J 0
(-6225 5725);
DISPLAY INVISIBLE (-6225 5725);
FORCEPROP 1 LAST PATH I58
J 0
(-6227 5725);
DISPLAY 0.872340 (-6227 5725);
PAINT GREEN (-6227 5725);
DISPLAY INVISIBLE (-6227 5725);
FORCEPROP 1 LAST HDL_TAP TRUE
J 0
(-5900 5600);
DISPLAY 0.574468 (-5900 5600);
PAINT GREEN (-5900 5600);
DISPLAY INVISIBLE (-5900 5600);
FORCEPROP 1 LAST BODY_TYPE PLUMBING
J 0
(-6225 5675);
DISPLAY 0.574468 (-6225 5675);
PAINT GREEN (-6225 5675);
DISPLAY INVISIBLE (-6225 5675);
FORCEADD TAP..6
R 2
(-4500 4425);
FORCEPROP 3 LASTPIN (-4550 4425) SIG_NAME P5E_CPU0_G3_TX_C_DP<13>
J 0
(-4540 4435);
DISPLAY 0.659574 (-4540 4435);
PAINT MONO (-4540 4435);
DISPLAY INVISIBLE (-4540 4435);
FORCEPROP 1 LASTPIN (-4550 4425) BN 13
J 2
(-4498 4433);
DISPLAY 0.680851 (-4498 4433);
PAINT MONO (-4498 4433);
FORCEPROP 2 LAST CDS_LIB standard
J 0
(-4500 4425);
DISPLAY INVISIBLE (-4500 4425);
FORCEPROP 1 LAST PATH I68
J 2
(-4498 4425);
DISPLAY 0.872340 (-4498 4425);
PAINT GREEN (-4498 4425);
DISPLAY INVISIBLE (-4498 4425);
FORCEPROP 2 LAST BOM_COST IO_SLOT
J 0
(-5000 4525);
DISPLAY 0.829787 (-5000 4525);
DISPLAY INVISIBLE (-5000 4525);
FORCEPROP 1 LAST BODY_TYPE PLUMBING
J 2
(-4500 4375);
DISPLAY 0.702128 (-4500 4375);
PAINT GREEN (-4500 4375);
DISPLAY INVISIBLE (-4500 4375);
FORCEPROP 1 LAST HDL_TAP TRUE
J 2
(-4825 4300);
DISPLAY 0.702128 (-4825 4300);
PAINT GREEN (-4825 4300);
DISPLAY INVISIBLE (-4825 4300);
FORCEPROP 2 LAST ROOM RISER1
J 0
(-5000 4475);
DISPLAY 0.829787 (-5000 4475);
PAINT RED (-5000 4475);
DISPLAY INVISIBLE (-5000 4475);
FORCEADD TAP..6
R 2
(-4500 4325);
FORCEPROP 3 LASTPIN (-4550 4325) SIG_NAME P5E_CPU0_G3_TX_C_DP<14>
J 0
(-4540 4335);
DISPLAY 0.659574 (-4540 4335);
PAINT MONO (-4540 4335);
DISPLAY INVISIBLE (-4540 4335);
FORCEPROP 1 LASTPIN (-4550 4325) BN 14
J 2
(-4498 4333);
DISPLAY 0.680851 (-4498 4333);
PAINT MONO (-4498 4333);
FORCEPROP 2 LAST CDS_LIB standard
J 0
(-4500 4325);
DISPLAY INVISIBLE (-4500 4325);
FORCEPROP 1 LAST PATH I69
J 2
(-4498 4325);
DISPLAY 0.872340 (-4498 4325);
PAINT GREEN (-4498 4325);
DISPLAY INVISIBLE (-4498 4325);
FORCEPROP 2 LAST BOM_COST IO_SLOT
J 0
(-5000 4425);
DISPLAY 0.829787 (-5000 4425);
DISPLAY INVISIBLE (-5000 4425);
FORCEPROP 1 LAST BODY_TYPE PLUMBING
J 2
(-4500 4275);
DISPLAY 0.702128 (-4500 4275);
PAINT GREEN (-4500 4275);
DISPLAY INVISIBLE (-4500 4275);
FORCEPROP 1 LAST HDL_TAP TRUE
J 2
(-4825 4200);
DISPLAY 0.702128 (-4825 4200);
PAINT GREEN (-4825 4200);
DISPLAY INVISIBLE (-4825 4200);
FORCEPROP 2 LAST ROOM RISER1
J 0
(-5000 4375);
DISPLAY 0.829787 (-5000 4375);
PAINT RED (-5000 4375);
DISPLAY INVISIBLE (-5000 4375);
FORCEADD OFFPAGE..1
(-7325 5950);
FORCEPROP 2 LAST CDS_LIB standard
J 0
(-7325 5950);
DISPLAY INVISIBLE (-7325 5950);
FORCEPROP 2 LAST PATH I7
J 0
(-7275 6025);
DISPLAY 0.680851 (-7275 6025);
DISPLAY INVISIBLE (-7275 6025);
FORCEPROP 1 LAST COMMENT_BODY TRUE
J 0
(-7200 5850);
DISPLAY 0.872340 (-7200 5850);
PAINT GREEN (-7200 5850);
DISPLAY INVISIBLE (-7200 5850);
FORCEPROP 1 LAST OFFPAGE TRUE
J 0
(-7000 5825);
DISPLAY 0.872340 (-7000 5825);
PAINT GREEN (-7000 5825);
DISPLAY INVISIBLE (-7000 5825);
FORCEADD TAP..6
R 2
(-4500 4625);
FORCEPROP 3 LASTPIN (-4550 4625) SIG_NAME P5E_CPU0_G3_TX_C_DP<11>
J 0
(-4540 4635);
DISPLAY 0.659574 (-4540 4635);
PAINT MONO (-4540 4635);
DISPLAY INVISIBLE (-4540 4635);
FORCEPROP 1 LASTPIN (-4550 4625) BN 11
J 2
(-4498 4633);
DISPLAY 0.680851 (-4498 4633);
PAINT MONO (-4498 4633);
FORCEPROP 2 LAST CDS_LIB standard
J 0
(-4500 4625);
DISPLAY INVISIBLE (-4500 4625);
FORCEPROP 1 LAST PATH I70
J 2
(-4498 4625);
DISPLAY 0.872340 (-4498 4625);
PAINT GREEN (-4498 4625);
DISPLAY INVISIBLE (-4498 4625);
FORCEPROP 2 LAST BOM_COST IO_SLOT
J 0
(-5000 4725);
DISPLAY 0.829787 (-5000 4725);
DISPLAY INVISIBLE (-5000 4725);
FORCEPROP 1 LAST BODY_TYPE PLUMBING
J 2
(-4500 4575);
DISPLAY 0.702128 (-4500 4575);
PAINT GREEN (-4500 4575);
DISPLAY INVISIBLE (-4500 4575);
FORCEPROP 1 LAST HDL_TAP TRUE
J 2
(-4825 4500);
DISPLAY 0.702128 (-4825 4500);
PAINT GREEN (-4825 4500);
DISPLAY INVISIBLE (-4825 4500);
FORCEPROP 2 LAST ROOM RISER1
J 0
(-5000 4675);
DISPLAY 0.829787 (-5000 4675);
PAINT RED (-5000 4675);
DISPLAY INVISIBLE (-5000 4675);
FORCEADD TAP..6
R 2
(-4500 4725);
FORCEPROP 3 LASTPIN (-4550 4725) SIG_NAME P5E_CPU0_G3_TX_C_DP<10>
J 0
(-4540 4735);
DISPLAY 0.659574 (-4540 4735);
PAINT MONO (-4540 4735);
DISPLAY INVISIBLE (-4540 4735);
FORCEPROP 1 LASTPIN (-4550 4725) BN 10
J 2
(-4498 4733);
DISPLAY 0.680851 (-4498 4733);
PAINT MONO (-4498 4733);
FORCEPROP 2 LAST CDS_LIB standard
J 0
(-4500 4725);
DISPLAY INVISIBLE (-4500 4725);
FORCEPROP 1 LAST PATH I71
J 2
(-4498 4725);
DISPLAY 0.872340 (-4498 4725);
PAINT GREEN (-4498 4725);
DISPLAY INVISIBLE (-4498 4725);
FORCEPROP 2 LAST BOM_COST IO_SLOT
J 0
(-5000 4825);
DISPLAY 0.829787 (-5000 4825);
DISPLAY INVISIBLE (-5000 4825);
FORCEPROP 1 LAST BODY_TYPE PLUMBING
J 2
(-4500 4675);
DISPLAY 0.702128 (-4500 4675);
PAINT GREEN (-4500 4675);
DISPLAY INVISIBLE (-4500 4675);
FORCEPROP 1 LAST HDL_TAP TRUE
J 2
(-4825 4600);
DISPLAY 0.702128 (-4825 4600);
PAINT GREEN (-4825 4600);
DISPLAY INVISIBLE (-4825 4600);
FORCEPROP 2 LAST ROOM RISER1
J 0
(-5000 4775);
DISPLAY 0.829787 (-5000 4775);
PAINT RED (-5000 4775);
DISPLAY INVISIBLE (-5000 4775);
FORCEADD TAP..6
R 2
(-4500 4525);
FORCEPROP 3 LASTPIN (-4550 4525) SIG_NAME P5E_CPU0_G3_TX_C_DP<12>
J 0
(-4540 4535);
DISPLAY 0.659574 (-4540 4535);
PAINT MONO (-4540 4535);
DISPLAY INVISIBLE (-4540 4535);
FORCEPROP 1 LASTPIN (-4550 4525) BN 12
J 2
(-4498 4533);
DISPLAY 0.680851 (-4498 4533);
PAINT MONO (-4498 4533);
FORCEPROP 2 LAST CDS_LIB standard
J 0
(-4500 4525);
DISPLAY INVISIBLE (-4500 4525);
FORCEPROP 1 LAST PATH I72
J 2
(-4498 4525);
DISPLAY 0.872340 (-4498 4525);
PAINT GREEN (-4498 4525);
DISPLAY INVISIBLE (-4498 4525);
FORCEPROP 2 LAST BOM_COST IO_SLOT
J 0
(-5000 4625);
DISPLAY 0.829787 (-5000 4625);
DISPLAY INVISIBLE (-5000 4625);
FORCEPROP 1 LAST BODY_TYPE PLUMBING
J 2
(-4500 4475);
DISPLAY 0.702128 (-4500 4475);
PAINT GREEN (-4500 4475);
DISPLAY INVISIBLE (-4500 4475);
FORCEPROP 1 LAST HDL_TAP TRUE
J 2
(-4825 4400);
DISPLAY 0.702128 (-4825 4400);
PAINT GREEN (-4825 4400);
DISPLAY INVISIBLE (-4825 4400);
FORCEPROP 2 LAST ROOM RISER1
J 0
(-5000 4575);
DISPLAY 0.829787 (-5000 4575);
PAINT RED (-5000 4575);
DISPLAY INVISIBLE (-5000 4575);
FORCEADD TAP..6
R 2
(-4500 4925);
FORCEPROP 3 LASTPIN (-4550 4925) SIG_NAME P5E_CPU0_G3_TX_C_DP<8>
J 0
(-4540 4935);
DISPLAY 0.659574 (-4540 4935);
PAINT MONO (-4540 4935);
DISPLAY INVISIBLE (-4540 4935);
FORCEPROP 1 LASTPIN (-4550 4925) BN 8
J 2
(-4498 4933);
DISPLAY 0.680851 (-4498 4933);
PAINT MONO (-4498 4933);
FORCEPROP 2 LAST CDS_LIB standard
J 0
(-4500 4925);
DISPLAY INVISIBLE (-4500 4925);
FORCEPROP 1 LAST PATH I73
J 2
(-4498 4925);
DISPLAY 0.872340 (-4498 4925);
PAINT GREEN (-4498 4925);
DISPLAY INVISIBLE (-4498 4925);
FORCEPROP 2 LAST BOM_COST IO_SLOT
J 0
(-5000 5025);
DISPLAY 0.829787 (-5000 5025);
DISPLAY INVISIBLE (-5000 5025);
FORCEPROP 1 LAST BODY_TYPE PLUMBING
J 2
(-4500 4875);
DISPLAY 0.702128 (-4500 4875);
PAINT GREEN (-4500 4875);
DISPLAY INVISIBLE (-4500 4875);
FORCEPROP 1 LAST HDL_TAP TRUE
J 2
(-4825 4800);
DISPLAY 0.702128 (-4825 4800);
PAINT GREEN (-4825 4800);
DISPLAY INVISIBLE (-4825 4800);
FORCEPROP 2 LAST ROOM RISER1
J 0
(-5000 4975);
DISPLAY 0.829787 (-5000 4975);
PAINT RED (-5000 4975);
DISPLAY INVISIBLE (-5000 4975);
FORCEADD TAP..6
R 2
(-4500 4825);
FORCEPROP 3 LASTPIN (-4550 4825) SIG_NAME P5E_CPU0_G3_TX_C_DP<9>
J 0
(-4540 4835);
DISPLAY 0.659574 (-4540 4835);
PAINT MONO (-4540 4835);
DISPLAY INVISIBLE (-4540 4835);
FORCEPROP 1 LASTPIN (-4550 4825) BN 9
J 2
(-4498 4833);
DISPLAY 0.680851 (-4498 4833);
PAINT MONO (-4498 4833);
FORCEPROP 2 LAST CDS_LIB standard
J 0
(-4500 4825);
DISPLAY INVISIBLE (-4500 4825);
FORCEPROP 1 LAST PATH I74
J 2
(-4498 4825);
DISPLAY 0.872340 (-4498 4825);
PAINT GREEN (-4498 4825);
DISPLAY INVISIBLE (-4498 4825);
FORCEPROP 2 LAST BOM_COST IO_SLOT
J 0
(-5000 4925);
DISPLAY 0.829787 (-5000 4925);
DISPLAY INVISIBLE (-5000 4925);
FORCEPROP 1 LAST BODY_TYPE PLUMBING
J 2
(-4500 4775);
DISPLAY 0.702128 (-4500 4775);
PAINT GREEN (-4500 4775);
DISPLAY INVISIBLE (-4500 4775);
FORCEPROP 1 LAST HDL_TAP TRUE
J 2
(-4825 4700);
DISPLAY 0.702128 (-4825 4700);
PAINT GREEN (-4825 4700);
DISPLAY INVISIBLE (-4825 4700);
FORCEPROP 2 LAST ROOM RISER1
J 0
(-5000 4875);
DISPLAY 0.829787 (-5000 4875);
PAINT RED (-5000 4875);
DISPLAY INVISIBLE (-5000 4875);
FORCEADD TAP..6
R 2
(-4500 5125);
FORCEPROP 3 LASTPIN (-4550 5125) SIG_NAME P5E_CPU0_G3_TX_C_DP<6>
J 0
(-4540 5135);
DISPLAY 0.659574 (-4540 5135);
PAINT MONO (-4540 5135);
DISPLAY INVISIBLE (-4540 5135);
FORCEPROP 1 LASTPIN (-4550 5125) BN 6
J 2
(-4498 5133);
DISPLAY 0.680851 (-4498 5133);
PAINT MONO (-4498 5133);
FORCEPROP 2 LAST CDS_LIB standard
J 0
(-4500 5125);
DISPLAY INVISIBLE (-4500 5125);
FORCEPROP 1 LAST PATH I75
J 2
(-4498 5125);
DISPLAY 0.872340 (-4498 5125);
PAINT GREEN (-4498 5125);
DISPLAY INVISIBLE (-4498 5125);
FORCEPROP 2 LAST BOM_COST IO_SLOT
J 0
(-5000 5225);
DISPLAY 0.829787 (-5000 5225);
DISPLAY INVISIBLE (-5000 5225);
FORCEPROP 1 LAST BODY_TYPE PLUMBING
J 2
(-4500 5075);
DISPLAY 0.702128 (-4500 5075);
PAINT GREEN (-4500 5075);
DISPLAY INVISIBLE (-4500 5075);
FORCEPROP 1 LAST HDL_TAP TRUE
J 2
(-4825 5000);
DISPLAY 0.702128 (-4825 5000);
PAINT GREEN (-4825 5000);
DISPLAY INVISIBLE (-4825 5000);
FORCEPROP 2 LAST ROOM RISER1
J 0
(-5000 5175);
DISPLAY 0.829787 (-5000 5175);
PAINT RED (-5000 5175);
DISPLAY INVISIBLE (-5000 5175);
FORCEADD TAP..6
R 2
(-4500 5225);
FORCEPROP 3 LASTPIN (-4550 5225) SIG_NAME P5E_CPU0_G3_TX_C_DP<5>
J 0
(-4540 5235);
DISPLAY 0.659574 (-4540 5235);
PAINT MONO (-4540 5235);
DISPLAY INVISIBLE (-4540 5235);
FORCEPROP 1 LASTPIN (-4550 5225) BN 5
J 2
(-4498 5233);
DISPLAY 0.680851 (-4498 5233);
PAINT MONO (-4498 5233);
FORCEPROP 2 LAST CDS_LIB standard
J 0
(-4500 5225);
DISPLAY INVISIBLE (-4500 5225);
FORCEPROP 1 LAST PATH I76
J 2
(-4498 5225);
DISPLAY 0.872340 (-4498 5225);
PAINT GREEN (-4498 5225);
DISPLAY INVISIBLE (-4498 5225);
FORCEPROP 2 LAST BOM_COST IO_SLOT
J 0
(-5000 5325);
DISPLAY 0.829787 (-5000 5325);
DISPLAY INVISIBLE (-5000 5325);
FORCEPROP 1 LAST BODY_TYPE PLUMBING
J 2
(-4500 5175);
DISPLAY 0.702128 (-4500 5175);
PAINT GREEN (-4500 5175);
DISPLAY INVISIBLE (-4500 5175);
FORCEPROP 1 LAST HDL_TAP TRUE
J 2
(-4825 5100);
DISPLAY 0.702128 (-4825 5100);
PAINT GREEN (-4825 5100);
DISPLAY INVISIBLE (-4825 5100);
FORCEPROP 2 LAST ROOM RISER1
J 0
(-5000 5275);
DISPLAY 0.829787 (-5000 5275);
PAINT RED (-5000 5275);
DISPLAY INVISIBLE (-5000 5275);
FORCEADD TAP..6
R 2
(-4500 5025);
FORCEPROP 3 LASTPIN (-4550 5025) SIG_NAME P5E_CPU0_G3_TX_C_DP<7>
J 0
(-4540 5035);
DISPLAY 0.659574 (-4540 5035);
PAINT MONO (-4540 5035);
DISPLAY INVISIBLE (-4540 5035);
FORCEPROP 1 LASTPIN (-4550 5025) BN 7
J 2
(-4498 5033);
DISPLAY 0.680851 (-4498 5033);
PAINT MONO (-4498 5033);
FORCEPROP 2 LAST CDS_LIB standard
J 0
(-4500 5025);
DISPLAY INVISIBLE (-4500 5025);
FORCEPROP 1 LAST PATH I77
J 2
(-4498 5025);
DISPLAY 0.872340 (-4498 5025);
PAINT GREEN (-4498 5025);
DISPLAY INVISIBLE (-4498 5025);
FORCEPROP 2 LAST BOM_COST IO_SLOT
J 0
(-5000 5125);
DISPLAY 0.829787 (-5000 5125);
DISPLAY INVISIBLE (-5000 5125);
FORCEPROP 1 LAST BODY_TYPE PLUMBING
J 2
(-4500 4975);
DISPLAY 0.702128 (-4500 4975);
PAINT GREEN (-4500 4975);
DISPLAY INVISIBLE (-4500 4975);
FORCEPROP 1 LAST HDL_TAP TRUE
J 2
(-4825 4900);
DISPLAY 0.702128 (-4825 4900);
PAINT GREEN (-4825 4900);
DISPLAY INVISIBLE (-4825 4900);
FORCEPROP 2 LAST ROOM RISER1
J 0
(-5000 5075);
DISPLAY 0.829787 (-5000 5075);
PAINT RED (-5000 5075);
DISPLAY INVISIBLE (-5000 5075);
FORCEADD TAP..6
R 2
(-4500 5525);
FORCEPROP 3 LASTPIN (-4550 5525) SIG_NAME P5E_CPU0_G3_TX_C_DP<2>
J 0
(-4540 5535);
DISPLAY 0.659574 (-4540 5535);
PAINT MONO (-4540 5535);
DISPLAY INVISIBLE (-4540 5535);
FORCEPROP 1 LASTPIN (-4550 5525) BN 2
J 2
(-4498 5533);
DISPLAY 0.680851 (-4498 5533);
PAINT MONO (-4498 5533);
FORCEPROP 2 LAST CDS_LIB standard
J 0
(-4500 5525);
DISPLAY INVISIBLE (-4500 5525);
FORCEPROP 1 LAST PATH I78
J 2
(-4498 5525);
DISPLAY 0.872340 (-4498 5525);
PAINT GREEN (-4498 5525);
DISPLAY INVISIBLE (-4498 5525);
FORCEPROP 2 LAST BOM_COST IO_SLOT
J 0
(-5000 5625);
DISPLAY 0.829787 (-5000 5625);
DISPLAY INVISIBLE (-5000 5625);
FORCEPROP 1 LAST BODY_TYPE PLUMBING
J 2
(-4500 5475);
DISPLAY 0.702128 (-4500 5475);
PAINT GREEN (-4500 5475);
DISPLAY INVISIBLE (-4500 5475);
FORCEPROP 1 LAST HDL_TAP TRUE
J 2
(-4825 5400);
DISPLAY 0.702128 (-4825 5400);
PAINT GREEN (-4825 5400);
DISPLAY INVISIBLE (-4825 5400);
FORCEPROP 2 LAST ROOM RISER1
J 0
(-5000 5575);
DISPLAY 0.829787 (-5000 5575);
PAINT RED (-5000 5575);
DISPLAY INVISIBLE (-5000 5575);
FORCEADD TAP..6
R 2
(-4500 5325);
FORCEPROP 3 LASTPIN (-4550 5325) SIG_NAME P5E_CPU0_G3_TX_C_DP<4>
J 0
(-4540 5335);
DISPLAY 0.659574 (-4540 5335);
PAINT MONO (-4540 5335);
DISPLAY INVISIBLE (-4540 5335);
FORCEPROP 1 LASTPIN (-4550 5325) BN 4
J 2
(-4498 5333);
DISPLAY 0.680851 (-4498 5333);
PAINT MONO (-4498 5333);
FORCEPROP 2 LAST CDS_LIB standard
J 0
(-4500 5325);
DISPLAY INVISIBLE (-4500 5325);
FORCEPROP 1 LAST PATH I79
J 2
(-4498 5325);
DISPLAY 0.872340 (-4498 5325);
PAINT GREEN (-4498 5325);
DISPLAY INVISIBLE (-4498 5325);
FORCEPROP 2 LAST BOM_COST IO_SLOT
J 0
(-5000 5425);
DISPLAY 0.829787 (-5000 5425);
DISPLAY INVISIBLE (-5000 5425);
FORCEPROP 1 LAST BODY_TYPE PLUMBING
J 2
(-4500 5275);
DISPLAY 0.702128 (-4500 5275);
PAINT GREEN (-4500 5275);
DISPLAY INVISIBLE (-4500 5275);
FORCEPROP 1 LAST HDL_TAP TRUE
J 2
(-4825 5200);
DISPLAY 0.702128 (-4825 5200);
PAINT GREEN (-4825 5200);
DISPLAY INVISIBLE (-4825 5200);
FORCEPROP 2 LAST ROOM RISER1
J 0
(-5000 5375);
DISPLAY 0.829787 (-5000 5375);
PAINT RED (-5000 5375);
DISPLAY INVISIBLE (-5000 5375);
FORCEADD OFFPAGE..1
(-7325 5900);
FORCEPROP 2 LAST CDS_LIB standard
J 0
(-7325 5900);
DISPLAY INVISIBLE (-7325 5900);
FORCEPROP 2 LAST PATH I8
J 0
(-7275 5975);
DISPLAY 0.680851 (-7275 5975);
DISPLAY INVISIBLE (-7275 5975);
FORCEPROP 1 LAST COMMENT_BODY TRUE
J 0
(-7200 5800);
DISPLAY 0.872340 (-7200 5800);
PAINT GREEN (-7200 5800);
DISPLAY INVISIBLE (-7200 5800);
FORCEPROP 1 LAST OFFPAGE TRUE
J 0
(-7000 5775);
DISPLAY 0.872340 (-7000 5775);
PAINT GREEN (-7000 5775);
DISPLAY INVISIBLE (-7000 5775);
FORCEADD TAP..6
R 2
(-4500 5425);
FORCEPROP 3 LASTPIN (-4550 5425) SIG_NAME P5E_CPU0_G3_TX_C_DP<3>
J 0
(-4540 5435);
DISPLAY 0.659574 (-4540 5435);
PAINT MONO (-4540 5435);
DISPLAY INVISIBLE (-4540 5435);
FORCEPROP 1 LASTPIN (-4550 5425) BN 3
J 2
(-4498 5433);
DISPLAY 0.680851 (-4498 5433);
PAINT MONO (-4498 5433);
FORCEPROP 2 LAST CDS_LIB standard
J 0
(-4500 5425);
DISPLAY INVISIBLE (-4500 5425);
FORCEPROP 1 LAST PATH I80
J 2
(-4498 5425);
DISPLAY 0.872340 (-4498 5425);
PAINT GREEN (-4498 5425);
DISPLAY INVISIBLE (-4498 5425);
FORCEPROP 2 LAST BOM_COST IO_SLOT
J 0
(-5000 5525);
DISPLAY 0.829787 (-5000 5525);
DISPLAY INVISIBLE (-5000 5525);
FORCEPROP 1 LAST BODY_TYPE PLUMBING
J 2
(-4500 5375);
DISPLAY 0.702128 (-4500 5375);
PAINT GREEN (-4500 5375);
DISPLAY INVISIBLE (-4500 5375);
FORCEPROP 1 LAST HDL_TAP TRUE
J 2
(-4825 5300);
DISPLAY 0.702128 (-4825 5300);
PAINT GREEN (-4825 5300);
DISPLAY INVISIBLE (-4825 5300);
FORCEPROP 2 LAST ROOM RISER1
J 0
(-5000 5475);
DISPLAY 0.829787 (-5000 5475);
PAINT RED (-5000 5475);
DISPLAY INVISIBLE (-5000 5475);
FORCEADD TAP..6
R 2
(-4500 5725);
FORCEPROP 3 LASTPIN (-4550 5725) SIG_NAME P5E_CPU0_G3_TX_C_DP<0>
J 0
(-4540 5735);
DISPLAY 0.659574 (-4540 5735);
PAINT MONO (-4540 5735);
DISPLAY INVISIBLE (-4540 5735);
FORCEPROP 1 LASTPIN (-4550 5725) BN 0
J 2
(-4498 5733);
DISPLAY 0.680851 (-4498 5733);
PAINT MONO (-4498 5733);
FORCEPROP 2 LAST CDS_LIB standard
J 0
(-4500 5725);
DISPLAY INVISIBLE (-4500 5725);
FORCEPROP 1 LAST PATH I81
J 2
(-4498 5725);
DISPLAY 0.872340 (-4498 5725);
PAINT GREEN (-4498 5725);
DISPLAY INVISIBLE (-4498 5725);
FORCEPROP 2 LAST BOM_COST IO_SLOT
J 0
(-5000 5825);
DISPLAY 0.829787 (-5000 5825);
DISPLAY INVISIBLE (-5000 5825);
FORCEPROP 1 LAST BODY_TYPE PLUMBING
J 2
(-4500 5675);
DISPLAY 0.702128 (-4500 5675);
PAINT GREEN (-4500 5675);
DISPLAY INVISIBLE (-4500 5675);
FORCEPROP 1 LAST HDL_TAP TRUE
J 2
(-4825 5600);
DISPLAY 0.702128 (-4825 5600);
PAINT GREEN (-4825 5600);
DISPLAY INVISIBLE (-4825 5600);
FORCEPROP 2 LAST ROOM RISER1
J 0
(-5000 5775);
DISPLAY 0.829787 (-5000 5775);
PAINT RED (-5000 5775);
DISPLAY INVISIBLE (-5000 5775);
FORCEADD TAP..6
R 2
(-4500 5625);
FORCEPROP 3 LASTPIN (-4550 5625) SIG_NAME P5E_CPU0_G3_TX_C_DP<1>
J 0
(-4540 5635);
DISPLAY 0.659574 (-4540 5635);
PAINT MONO (-4540 5635);
DISPLAY INVISIBLE (-4540 5635);
FORCEPROP 1 LASTPIN (-4550 5625) BN 1
J 2
(-4498 5633);
DISPLAY 0.680851 (-4498 5633);
PAINT MONO (-4498 5633);
FORCEPROP 2 LAST CDS_LIB standard
J 0
(-4500 5625);
DISPLAY INVISIBLE (-4500 5625);
FORCEPROP 1 LAST PATH I82
J 2
(-4498 5625);
DISPLAY 0.872340 (-4498 5625);
PAINT GREEN (-4498 5625);
DISPLAY INVISIBLE (-4498 5625);
FORCEPROP 2 LAST BOM_COST IO_SLOT
J 0
(-5000 5725);
DISPLAY 0.829787 (-5000 5725);
DISPLAY INVISIBLE (-5000 5725);
FORCEPROP 1 LAST BODY_TYPE PLUMBING
J 2
(-4500 5575);
DISPLAY 0.702128 (-4500 5575);
PAINT GREEN (-4500 5575);
DISPLAY INVISIBLE (-4500 5575);
FORCEPROP 1 LAST HDL_TAP TRUE
J 2
(-4825 5500);
DISPLAY 0.702128 (-4825 5500);
PAINT GREEN (-4825 5500);
DISPLAY INVISIBLE (-4825 5500);
FORCEPROP 2 LAST ROOM RISER1
J 0
(-5000 5675);
DISPLAY 0.829787 (-5000 5675);
PAINT RED (-5000 5675);
DISPLAY INVISIBLE (-5000 5675);
FORCEADD TAP..6
R 2
(-4350 4175);
FORCEPROP 3 LASTPIN (-4400 4175) SIG_NAME P5E_CPU0_G3_TX_C_DN<15>
J 0
(-4390 4185);
DISPLAY 0.659574 (-4390 4185);
PAINT MONO (-4390 4185);
DISPLAY INVISIBLE (-4390 4185);
FORCEPROP 1 LASTPIN (-4400 4175) BN 15
J 2
(-4348 4183);
DISPLAY 0.680851 (-4348 4183);
PAINT MONO (-4348 4183);
FORCEPROP 2 LAST CDS_LIB standard
J 0
(-4350 4175);
DISPLAY INVISIBLE (-4350 4175);
FORCEPROP 1 LAST PATH I83
J 2
(-4348 4175);
DISPLAY 0.872340 (-4348 4175);
PAINT GREEN (-4348 4175);
DISPLAY INVISIBLE (-4348 4175);
FORCEPROP 2 LAST BOM_COST IO_SLOT
J 0
(-4850 4275);
DISPLAY 0.829787 (-4850 4275);
DISPLAY INVISIBLE (-4850 4275);
FORCEPROP 1 LAST BODY_TYPE PLUMBING
J 2
(-4350 4125);
DISPLAY 0.702128 (-4350 4125);
PAINT GREEN (-4350 4125);
DISPLAY INVISIBLE (-4350 4125);
FORCEPROP 1 LAST HDL_TAP TRUE
J 2
(-4675 4050);
DISPLAY 0.702128 (-4675 4050);
PAINT GREEN (-4675 4050);
DISPLAY INVISIBLE (-4675 4050);
FORCEPROP 2 LAST ROOM RISER1
J 0
(-4850 4225);
DISPLAY 0.829787 (-4850 4225);
PAINT RED (-4850 4225);
DISPLAY INVISIBLE (-4850 4225);
FORCEADD TAP..6
R 2
(-4350 4275);
FORCEPROP 3 LASTPIN (-4400 4275) SIG_NAME P5E_CPU0_G3_TX_C_DN<14>
J 0
(-4390 4285);
DISPLAY 0.659574 (-4390 4285);
PAINT MONO (-4390 4285);
DISPLAY INVISIBLE (-4390 4285);
FORCEPROP 1 LASTPIN (-4400 4275) BN 14
J 2
(-4348 4283);
DISPLAY 0.680851 (-4348 4283);
PAINT MONO (-4348 4283);
FORCEPROP 2 LAST CDS_LIB standard
J 0
(-4350 4275);
DISPLAY INVISIBLE (-4350 4275);
FORCEPROP 1 LAST PATH I84
J 2
(-4348 4275);
DISPLAY 0.872340 (-4348 4275);
PAINT GREEN (-4348 4275);
DISPLAY INVISIBLE (-4348 4275);
FORCEPROP 2 LAST BOM_COST IO_SLOT
J 0
(-4850 4375);
DISPLAY 0.829787 (-4850 4375);
DISPLAY INVISIBLE (-4850 4375);
FORCEPROP 1 LAST BODY_TYPE PLUMBING
J 2
(-4350 4225);
DISPLAY 0.702128 (-4350 4225);
PAINT GREEN (-4350 4225);
DISPLAY INVISIBLE (-4350 4225);
FORCEPROP 1 LAST HDL_TAP TRUE
J 2
(-4675 4150);
DISPLAY 0.702128 (-4675 4150);
PAINT GREEN (-4675 4150);
DISPLAY INVISIBLE (-4675 4150);
FORCEPROP 2 LAST ROOM RISER1
J 0
(-4850 4325);
DISPLAY 0.829787 (-4850 4325);
PAINT RED (-4850 4325);
DISPLAY INVISIBLE (-4850 4325);
FORCEADD TAP..6
R 2
(-4350 4375);
FORCEPROP 3 LASTPIN (-4400 4375) SIG_NAME P5E_CPU0_G3_TX_C_DN<13>
J 0
(-4390 4385);
DISPLAY 0.659574 (-4390 4385);
PAINT MONO (-4390 4385);
DISPLAY INVISIBLE (-4390 4385);
FORCEPROP 1 LASTPIN (-4400 4375) BN 13
J 2
(-4348 4383);
DISPLAY 0.680851 (-4348 4383);
PAINT MONO (-4348 4383);
FORCEPROP 2 LAST CDS_LIB standard
J 0
(-4350 4375);
DISPLAY INVISIBLE (-4350 4375);
FORCEPROP 1 LAST PATH I85
J 2
(-4348 4375);
DISPLAY 0.872340 (-4348 4375);
PAINT GREEN (-4348 4375);
DISPLAY INVISIBLE (-4348 4375);
FORCEPROP 2 LAST BOM_COST IO_SLOT
J 0
(-4850 4475);
DISPLAY 0.829787 (-4850 4475);
DISPLAY INVISIBLE (-4850 4475);
FORCEPROP 1 LAST BODY_TYPE PLUMBING
J 2
(-4350 4325);
DISPLAY 0.702128 (-4350 4325);
PAINT GREEN (-4350 4325);
DISPLAY INVISIBLE (-4350 4325);
FORCEPROP 1 LAST HDL_TAP TRUE
J 2
(-4675 4250);
DISPLAY 0.702128 (-4675 4250);
PAINT GREEN (-4675 4250);
DISPLAY INVISIBLE (-4675 4250);
FORCEPROP 2 LAST ROOM RISER1
J 0
(-4850 4425);
DISPLAY 0.829787 (-4850 4425);
PAINT RED (-4850 4425);
DISPLAY INVISIBLE (-4850 4425);
FORCEADD TAP..6
R 2
(-4350 4475);
FORCEPROP 3 LASTPIN (-4400 4475) SIG_NAME P5E_CPU0_G3_TX_C_DN<12>
J 0
(-4390 4485);
DISPLAY 0.659574 (-4390 4485);
PAINT MONO (-4390 4485);
DISPLAY INVISIBLE (-4390 4485);
FORCEPROP 1 LASTPIN (-4400 4475) BN 12
J 2
(-4348 4483);
DISPLAY 0.680851 (-4348 4483);
PAINT MONO (-4348 4483);
FORCEPROP 2 LAST CDS_LIB standard
J 0
(-4350 4475);
DISPLAY INVISIBLE (-4350 4475);
FORCEPROP 1 LAST PATH I86
J 2
(-4348 4475);
DISPLAY 0.872340 (-4348 4475);
PAINT GREEN (-4348 4475);
DISPLAY INVISIBLE (-4348 4475);
FORCEPROP 2 LAST BOM_COST IO_SLOT
J 0
(-4850 4575);
DISPLAY 0.829787 (-4850 4575);
DISPLAY INVISIBLE (-4850 4575);
FORCEPROP 1 LAST BODY_TYPE PLUMBING
J 2
(-4350 4425);
DISPLAY 0.702128 (-4350 4425);
PAINT GREEN (-4350 4425);
DISPLAY INVISIBLE (-4350 4425);
FORCEPROP 1 LAST HDL_TAP TRUE
J 2
(-4675 4350);
DISPLAY 0.702128 (-4675 4350);
PAINT GREEN (-4675 4350);
DISPLAY INVISIBLE (-4675 4350);
FORCEPROP 2 LAST ROOM RISER1
J 0
(-4850 4525);
DISPLAY 0.829787 (-4850 4525);
PAINT RED (-4850 4525);
DISPLAY INVISIBLE (-4850 4525);
FORCEADD TAP..6
R 2
(-4350 4575);
FORCEPROP 3 LASTPIN (-4400 4575) SIG_NAME P5E_CPU0_G3_TX_C_DN<11>
J 0
(-4390 4585);
DISPLAY 0.659574 (-4390 4585);
PAINT MONO (-4390 4585);
DISPLAY INVISIBLE (-4390 4585);
FORCEPROP 1 LASTPIN (-4400 4575) BN 11
J 2
(-4348 4583);
DISPLAY 0.680851 (-4348 4583);
PAINT MONO (-4348 4583);
FORCEPROP 2 LAST CDS_LIB standard
J 0
(-4350 4575);
DISPLAY INVISIBLE (-4350 4575);
FORCEPROP 1 LAST PATH I87
J 2
(-4348 4575);
DISPLAY 0.872340 (-4348 4575);
PAINT GREEN (-4348 4575);
DISPLAY INVISIBLE (-4348 4575);
FORCEPROP 2 LAST BOM_COST IO_SLOT
J 0
(-4850 4675);
DISPLAY 0.829787 (-4850 4675);
DISPLAY INVISIBLE (-4850 4675);
FORCEPROP 1 LAST BODY_TYPE PLUMBING
J 2
(-4350 4525);
DISPLAY 0.702128 (-4350 4525);
PAINT GREEN (-4350 4525);
DISPLAY INVISIBLE (-4350 4525);
FORCEPROP 1 LAST HDL_TAP TRUE
J 2
(-4675 4450);
DISPLAY 0.702128 (-4675 4450);
PAINT GREEN (-4675 4450);
DISPLAY INVISIBLE (-4675 4450);
FORCEPROP 2 LAST ROOM RISER1
J 0
(-4850 4625);
DISPLAY 0.829787 (-4850 4625);
PAINT RED (-4850 4625);
DISPLAY INVISIBLE (-4850 4625);
FORCEADD TAP..6
R 2
(-4350 4675);
FORCEPROP 3 LASTPIN (-4400 4675) SIG_NAME P5E_CPU0_G3_TX_C_DN<10>
J 0
(-4390 4685);
DISPLAY 0.659574 (-4390 4685);
PAINT MONO (-4390 4685);
DISPLAY INVISIBLE (-4390 4685);
FORCEPROP 1 LASTPIN (-4400 4675) BN 10
J 2
(-4348 4683);
DISPLAY 0.680851 (-4348 4683);
PAINT MONO (-4348 4683);
FORCEPROP 2 LAST CDS_LIB standard
J 0
(-4350 4675);
DISPLAY INVISIBLE (-4350 4675);
FORCEPROP 1 LAST PATH I88
J 2
(-4348 4675);
DISPLAY 0.872340 (-4348 4675);
PAINT GREEN (-4348 4675);
DISPLAY INVISIBLE (-4348 4675);
FORCEPROP 2 LAST BOM_COST IO_SLOT
J 0
(-4850 4775);
DISPLAY 0.829787 (-4850 4775);
DISPLAY INVISIBLE (-4850 4775);
FORCEPROP 1 LAST BODY_TYPE PLUMBING
J 2
(-4350 4625);
DISPLAY 0.702128 (-4350 4625);
PAINT GREEN (-4350 4625);
DISPLAY INVISIBLE (-4350 4625);
FORCEPROP 1 LAST HDL_TAP TRUE
J 2
(-4675 4550);
DISPLAY 0.702128 (-4675 4550);
PAINT GREEN (-4675 4550);
DISPLAY INVISIBLE (-4675 4550);
FORCEPROP 2 LAST ROOM RISER1
J 0
(-4850 4725);
DISPLAY 0.829787 (-4850 4725);
PAINT RED (-4850 4725);
DISPLAY INVISIBLE (-4850 4725);
FORCEADD TAP..6
R 2
(-4350 4875);
FORCEPROP 3 LASTPIN (-4400 4875) SIG_NAME P5E_CPU0_G3_TX_C_DN<8>
J 0
(-4390 4885);
DISPLAY 0.659574 (-4390 4885);
PAINT MONO (-4390 4885);
DISPLAY INVISIBLE (-4390 4885);
FORCEPROP 1 LASTPIN (-4400 4875) BN 8
J 2
(-4348 4883);
DISPLAY 0.680851 (-4348 4883);
PAINT MONO (-4348 4883);
FORCEPROP 2 LAST CDS_LIB standard
J 0
(-4350 4875);
DISPLAY INVISIBLE (-4350 4875);
FORCEPROP 1 LAST PATH I89
J 2
(-4348 4875);
DISPLAY 0.872340 (-4348 4875);
PAINT GREEN (-4348 4875);
DISPLAY INVISIBLE (-4348 4875);
FORCEPROP 2 LAST BOM_COST IO_SLOT
J 0
(-4850 4975);
DISPLAY 0.829787 (-4850 4975);
DISPLAY INVISIBLE (-4850 4975);
FORCEPROP 1 LAST BODY_TYPE PLUMBING
J 2
(-4350 4825);
DISPLAY 0.702128 (-4350 4825);
PAINT GREEN (-4350 4825);
DISPLAY INVISIBLE (-4350 4825);
FORCEPROP 1 LAST HDL_TAP TRUE
J 2
(-4675 4750);
DISPLAY 0.702128 (-4675 4750);
PAINT GREEN (-4675 4750);
DISPLAY INVISIBLE (-4675 4750);
FORCEPROP 2 LAST ROOM RISER1
J 0
(-4850 4925);
DISPLAY 0.829787 (-4850 4925);
PAINT RED (-4850 4925);
DISPLAY INVISIBLE (-4850 4925);
FORCEADD TAP..6
(-6375 4275);
FORCEPROP 3 LASTPIN (-6325 4275) SIG_NAME P5E_CPU0_G3_TX_DN<14>
J 0
(-6315 4285);
DISPLAY 0.659574 (-6315 4285);
PAINT MONO (-6315 4285);
DISPLAY INVISIBLE (-6315 4285);
FORCEPROP 1 LASTPIN (-6325 4275) BN 14
J 0
(-6377 4283);
DISPLAY 0.680851 (-6377 4283);
PAINT MONO (-6377 4283);
FORCEPROP 2 LAST CDS_LIB standard
J 0
(-6375 4275);
DISPLAY INVISIBLE (-6375 4275);
FORCEPROP 1 LAST PATH I9
J 0
(-6377 4275);
DISPLAY 0.872340 (-6377 4275);
PAINT GREEN (-6377 4275);
DISPLAY INVISIBLE (-6377 4275);
FORCEPROP 1 LAST HDL_TAP TRUE
J 0
(-6050 4150);
DISPLAY 0.574468 (-6050 4150);
PAINT GREEN (-6050 4150);
DISPLAY INVISIBLE (-6050 4150);
FORCEPROP 1 LAST BODY_TYPE PLUMBING
J 0
(-6375 4225);
DISPLAY 0.574468 (-6375 4225);
PAINT GREEN (-6375 4225);
DISPLAY INVISIBLE (-6375 4225);
FORCEADD TAP..6
R 2
(-4350 4775);
FORCEPROP 3 LASTPIN (-4400 4775) SIG_NAME P5E_CPU0_G3_TX_C_DN<9>
J 0
(-4390 4785);
DISPLAY 0.659574 (-4390 4785);
PAINT MONO (-4390 4785);
DISPLAY INVISIBLE (-4390 4785);
FORCEPROP 1 LASTPIN (-4400 4775) BN 9
J 2
(-4348 4783);
DISPLAY 0.680851 (-4348 4783);
PAINT MONO (-4348 4783);
FORCEPROP 2 LAST CDS_LIB standard
J 0
(-4350 4775);
DISPLAY INVISIBLE (-4350 4775);
FORCEPROP 1 LAST PATH I90
J 2
(-4348 4775);
DISPLAY 0.872340 (-4348 4775);
PAINT GREEN (-4348 4775);
DISPLAY INVISIBLE (-4348 4775);
FORCEPROP 2 LAST BOM_COST IO_SLOT
J 0
(-4850 4875);
DISPLAY 0.829787 (-4850 4875);
DISPLAY INVISIBLE (-4850 4875);
FORCEPROP 1 LAST BODY_TYPE PLUMBING
J 2
(-4350 4725);
DISPLAY 0.702128 (-4350 4725);
PAINT GREEN (-4350 4725);
DISPLAY INVISIBLE (-4350 4725);
FORCEPROP 1 LAST HDL_TAP TRUE
J 2
(-4675 4650);
DISPLAY 0.702128 (-4675 4650);
PAINT GREEN (-4675 4650);
DISPLAY INVISIBLE (-4675 4650);
FORCEPROP 2 LAST ROOM RISER1
J 0
(-4850 4825);
DISPLAY 0.829787 (-4850 4825);
PAINT RED (-4850 4825);
DISPLAY INVISIBLE (-4850 4825);
FORCEADD TAP..6
R 2
(-4350 4975);
FORCEPROP 3 LASTPIN (-4400 4975) SIG_NAME P5E_CPU0_G3_TX_C_DN<7>
J 0
(-4390 4985);
DISPLAY 0.659574 (-4390 4985);
PAINT MONO (-4390 4985);
DISPLAY INVISIBLE (-4390 4985);
FORCEPROP 1 LASTPIN (-4400 4975) BN 7
J 2
(-4348 4983);
DISPLAY 0.680851 (-4348 4983);
PAINT MONO (-4348 4983);
FORCEPROP 2 LAST CDS_LIB standard
J 0
(-4350 4975);
DISPLAY INVISIBLE (-4350 4975);
FORCEPROP 1 LAST PATH I91
J 2
(-4348 4975);
DISPLAY 0.872340 (-4348 4975);
PAINT GREEN (-4348 4975);
DISPLAY INVISIBLE (-4348 4975);
FORCEPROP 2 LAST BOM_COST IO_SLOT
J 0
(-4850 5075);
DISPLAY 0.829787 (-4850 5075);
DISPLAY INVISIBLE (-4850 5075);
FORCEPROP 1 LAST BODY_TYPE PLUMBING
J 2
(-4350 4925);
DISPLAY 0.702128 (-4350 4925);
PAINT GREEN (-4350 4925);
DISPLAY INVISIBLE (-4350 4925);
FORCEPROP 1 LAST HDL_TAP TRUE
J 2
(-4675 4850);
DISPLAY 0.702128 (-4675 4850);
PAINT GREEN (-4675 4850);
DISPLAY INVISIBLE (-4675 4850);
FORCEPROP 2 LAST ROOM RISER1
J 0
(-4850 5025);
DISPLAY 0.829787 (-4850 5025);
PAINT RED (-4850 5025);
DISPLAY INVISIBLE (-4850 5025);
FORCEADD TAP..6
R 2
(-4350 5075);
FORCEPROP 3 LASTPIN (-4400 5075) SIG_NAME P5E_CPU0_G3_TX_C_DN<6>
J 0
(-4390 5085);
DISPLAY 0.659574 (-4390 5085);
PAINT MONO (-4390 5085);
DISPLAY INVISIBLE (-4390 5085);
FORCEPROP 1 LASTPIN (-4400 5075) BN 6
J 2
(-4348 5083);
DISPLAY 0.680851 (-4348 5083);
PAINT MONO (-4348 5083);
FORCEPROP 2 LAST CDS_LIB standard
J 0
(-4350 5075);
DISPLAY INVISIBLE (-4350 5075);
FORCEPROP 1 LAST PATH I92
J 2
(-4348 5075);
DISPLAY 0.872340 (-4348 5075);
PAINT GREEN (-4348 5075);
DISPLAY INVISIBLE (-4348 5075);
FORCEPROP 2 LAST BOM_COST IO_SLOT
J 0
(-4850 5175);
DISPLAY 0.829787 (-4850 5175);
DISPLAY INVISIBLE (-4850 5175);
FORCEPROP 1 LAST BODY_TYPE PLUMBING
J 2
(-4350 5025);
DISPLAY 0.702128 (-4350 5025);
PAINT GREEN (-4350 5025);
DISPLAY INVISIBLE (-4350 5025);
FORCEPROP 1 LAST HDL_TAP TRUE
J 2
(-4675 4950);
DISPLAY 0.702128 (-4675 4950);
PAINT GREEN (-4675 4950);
DISPLAY INVISIBLE (-4675 4950);
FORCEPROP 2 LAST ROOM RISER1
J 0
(-4850 5125);
DISPLAY 0.829787 (-4850 5125);
PAINT RED (-4850 5125);
DISPLAY INVISIBLE (-4850 5125);
FORCEADD TAP..6
R 2
(-4350 5175);
FORCEPROP 3 LASTPIN (-4400 5175) SIG_NAME P5E_CPU0_G3_TX_C_DN<5>
J 0
(-4390 5185);
DISPLAY 0.659574 (-4390 5185);
PAINT MONO (-4390 5185);
DISPLAY INVISIBLE (-4390 5185);
FORCEPROP 1 LASTPIN (-4400 5175) BN 5
J 2
(-4348 5183);
DISPLAY 0.680851 (-4348 5183);
PAINT MONO (-4348 5183);
FORCEPROP 2 LAST CDS_LIB standard
J 0
(-4350 5175);
DISPLAY INVISIBLE (-4350 5175);
FORCEPROP 1 LAST PATH I93
J 2
(-4348 5175);
DISPLAY 0.872340 (-4348 5175);
PAINT GREEN (-4348 5175);
DISPLAY INVISIBLE (-4348 5175);
FORCEPROP 2 LAST BOM_COST IO_SLOT
J 0
(-4850 5275);
DISPLAY 0.829787 (-4850 5275);
DISPLAY INVISIBLE (-4850 5275);
FORCEPROP 1 LAST BODY_TYPE PLUMBING
J 2
(-4350 5125);
DISPLAY 0.702128 (-4350 5125);
PAINT GREEN (-4350 5125);
DISPLAY INVISIBLE (-4350 5125);
FORCEPROP 1 LAST HDL_TAP TRUE
J 2
(-4675 5050);
DISPLAY 0.702128 (-4675 5050);
PAINT GREEN (-4675 5050);
DISPLAY INVISIBLE (-4675 5050);
FORCEPROP 2 LAST ROOM RISER1
J 0
(-4850 5225);
DISPLAY 0.829787 (-4850 5225);
PAINT RED (-4850 5225);
DISPLAY INVISIBLE (-4850 5225);
FORCEADD TAP..6
R 2
(-4350 5275);
FORCEPROP 3 LASTPIN (-4400 5275) SIG_NAME P5E_CPU0_G3_TX_C_DN<4>
J 0
(-4390 5285);
DISPLAY 0.659574 (-4390 5285);
PAINT MONO (-4390 5285);
DISPLAY INVISIBLE (-4390 5285);
FORCEPROP 1 LASTPIN (-4400 5275) BN 4
J 2
(-4348 5283);
DISPLAY 0.680851 (-4348 5283);
PAINT MONO (-4348 5283);
FORCEPROP 2 LAST CDS_LIB standard
J 0
(-4350 5275);
DISPLAY INVISIBLE (-4350 5275);
FORCEPROP 1 LAST PATH I94
J 2
(-4348 5275);
DISPLAY 0.872340 (-4348 5275);
PAINT GREEN (-4348 5275);
DISPLAY INVISIBLE (-4348 5275);
FORCEPROP 2 LAST BOM_COST IO_SLOT
J 0
(-4850 5375);
DISPLAY 0.829787 (-4850 5375);
DISPLAY INVISIBLE (-4850 5375);
FORCEPROP 1 LAST BODY_TYPE PLUMBING
J 2
(-4350 5225);
DISPLAY 0.702128 (-4350 5225);
PAINT GREEN (-4350 5225);
DISPLAY INVISIBLE (-4350 5225);
FORCEPROP 1 LAST HDL_TAP TRUE
J 2
(-4675 5150);
DISPLAY 0.702128 (-4675 5150);
PAINT GREEN (-4675 5150);
DISPLAY INVISIBLE (-4675 5150);
FORCEPROP 2 LAST ROOM RISER1
J 0
(-4850 5325);
DISPLAY 0.829787 (-4850 5325);
PAINT RED (-4850 5325);
DISPLAY INVISIBLE (-4850 5325);
FORCEADD TAP..6
R 2
(-4350 5375);
FORCEPROP 3 LASTPIN (-4400 5375) SIG_NAME P5E_CPU0_G3_TX_C_DN<3>
J 0
(-4390 5385);
DISPLAY 0.659574 (-4390 5385);
PAINT MONO (-4390 5385);
DISPLAY INVISIBLE (-4390 5385);
FORCEPROP 1 LASTPIN (-4400 5375) BN 3
J 2
(-4348 5383);
DISPLAY 0.680851 (-4348 5383);
PAINT MONO (-4348 5383);
FORCEPROP 2 LAST CDS_LIB standard
J 0
(-4350 5375);
DISPLAY INVISIBLE (-4350 5375);
FORCEPROP 1 LAST PATH I95
J 2
(-4348 5375);
DISPLAY 0.872340 (-4348 5375);
PAINT GREEN (-4348 5375);
DISPLAY INVISIBLE (-4348 5375);
FORCEPROP 2 LAST BOM_COST IO_SLOT
J 0
(-4850 5475);
DISPLAY 0.829787 (-4850 5475);
DISPLAY INVISIBLE (-4850 5475);
FORCEPROP 1 LAST BODY_TYPE PLUMBING
J 2
(-4350 5325);
DISPLAY 0.702128 (-4350 5325);
PAINT GREEN (-4350 5325);
DISPLAY INVISIBLE (-4350 5325);
FORCEPROP 1 LAST HDL_TAP TRUE
J 2
(-4675 5250);
DISPLAY 0.702128 (-4675 5250);
PAINT GREEN (-4675 5250);
DISPLAY INVISIBLE (-4675 5250);
FORCEPROP 2 LAST ROOM RISER1
J 0
(-4850 5425);
DISPLAY 0.829787 (-4850 5425);
PAINT RED (-4850 5425);
DISPLAY INVISIBLE (-4850 5425);
FORCEADD TAP..6
R 2
(-4350 5475);
FORCEPROP 3 LASTPIN (-4400 5475) SIG_NAME P5E_CPU0_G3_TX_C_DN<2>
J 0
(-4390 5485);
DISPLAY 0.659574 (-4390 5485);
PAINT MONO (-4390 5485);
DISPLAY INVISIBLE (-4390 5485);
FORCEPROP 1 LASTPIN (-4400 5475) BN 2
J 2
(-4348 5483);
DISPLAY 0.680851 (-4348 5483);
PAINT MONO (-4348 5483);
FORCEPROP 2 LAST CDS_LIB standard
J 0
(-4350 5475);
DISPLAY INVISIBLE (-4350 5475);
FORCEPROP 1 LAST PATH I96
J 2
(-4348 5475);
DISPLAY 0.872340 (-4348 5475);
PAINT GREEN (-4348 5475);
DISPLAY INVISIBLE (-4348 5475);
FORCEPROP 2 LAST BOM_COST IO_SLOT
J 0
(-4850 5575);
DISPLAY 0.829787 (-4850 5575);
DISPLAY INVISIBLE (-4850 5575);
FORCEPROP 1 LAST BODY_TYPE PLUMBING
J 2
(-4350 5425);
DISPLAY 0.702128 (-4350 5425);
PAINT GREEN (-4350 5425);
DISPLAY INVISIBLE (-4350 5425);
FORCEPROP 1 LAST HDL_TAP TRUE
J 2
(-4675 5350);
DISPLAY 0.702128 (-4675 5350);
PAINT GREEN (-4675 5350);
DISPLAY INVISIBLE (-4675 5350);
FORCEPROP 2 LAST ROOM RISER1
J 0
(-4850 5525);
DISPLAY 0.829787 (-4850 5525);
PAINT RED (-4850 5525);
DISPLAY INVISIBLE (-4850 5525);
FORCEADD TAP..6
R 2
(-4350 5575);
FORCEPROP 3 LASTPIN (-4400 5575) SIG_NAME P5E_CPU0_G3_TX_C_DN<1>
J 0
(-4390 5585);
DISPLAY 0.659574 (-4390 5585);
PAINT MONO (-4390 5585);
DISPLAY INVISIBLE (-4390 5585);
FORCEPROP 1 LASTPIN (-4400 5575) BN 1
J 2
(-4348 5583);
DISPLAY 0.680851 (-4348 5583);
PAINT MONO (-4348 5583);
FORCEPROP 2 LAST CDS_LIB standard
J 0
(-4350 5575);
DISPLAY INVISIBLE (-4350 5575);
FORCEPROP 1 LAST PATH I97
J 2
(-4348 5575);
DISPLAY 0.872340 (-4348 5575);
PAINT GREEN (-4348 5575);
DISPLAY INVISIBLE (-4348 5575);
FORCEPROP 2 LAST BOM_COST IO_SLOT
J 0
(-4850 5675);
DISPLAY 0.829787 (-4850 5675);
DISPLAY INVISIBLE (-4850 5675);
FORCEPROP 1 LAST BODY_TYPE PLUMBING
J 2
(-4350 5525);
DISPLAY 0.702128 (-4350 5525);
PAINT GREEN (-4350 5525);
DISPLAY INVISIBLE (-4350 5525);
FORCEPROP 1 LAST HDL_TAP TRUE
J 2
(-4675 5450);
DISPLAY 0.702128 (-4675 5450);
PAINT GREEN (-4675 5450);
DISPLAY INVISIBLE (-4675 5450);
FORCEPROP 2 LAST ROOM RISER1
J 0
(-4850 5625);
DISPLAY 0.829787 (-4850 5625);
PAINT RED (-4850 5625);
DISPLAY INVISIBLE (-4850 5625);
FORCEADD TAP..6
R 2
(-4350 5675);
FORCEPROP 3 LASTPIN (-4400 5675) SIG_NAME P5E_CPU0_G3_TX_C_DN<0>
J 0
(-4390 5685);
DISPLAY 0.659574 (-4390 5685);
PAINT MONO (-4390 5685);
DISPLAY INVISIBLE (-4390 5685);
FORCEPROP 1 LASTPIN (-4400 5675) BN 0
J 2
(-4348 5683);
DISPLAY 0.680851 (-4348 5683);
PAINT MONO (-4348 5683);
FORCEPROP 2 LAST CDS_LIB standard
J 0
(-4350 5675);
DISPLAY INVISIBLE (-4350 5675);
FORCEPROP 1 LAST PATH I98
J 2
(-4348 5675);
DISPLAY 0.872340 (-4348 5675);
PAINT GREEN (-4348 5675);
DISPLAY INVISIBLE (-4348 5675);
FORCEPROP 2 LAST BOM_COST IO_SLOT
J 0
(-4850 5775);
DISPLAY 0.829787 (-4850 5775);
DISPLAY INVISIBLE (-4850 5775);
FORCEPROP 1 LAST BODY_TYPE PLUMBING
J 2
(-4350 5625);
DISPLAY 0.702128 (-4350 5625);
PAINT GREEN (-4350 5625);
DISPLAY INVISIBLE (-4350 5625);
FORCEPROP 1 LAST HDL_TAP TRUE
J 2
(-4675 5550);
DISPLAY 0.702128 (-4675 5550);
PAINT GREEN (-4675 5550);
DISPLAY INVISIBLE (-4675 5550);
FORCEPROP 2 LAST ROOM RISER1
J 0
(-4850 5725);
DISPLAY 0.829787 (-4850 5725);
PAINT RED (-4850 5725);
DISPLAY INVISIBLE (-4850 5725);
FORCEADD OFFPAGE..2
(-3375 5900);
FORCEPROP 2 LAST CDS_LIB standard
J 0
(-3375 5900);
DISPLAY INVISIBLE (-3375 5900);
FORCEPROP 2 LAST PATH I99
J 0
(-3200 5975);
DISPLAY 0.680851 (-3200 5975);
DISPLAY INVISIBLE (-3200 5975);
FORCEPROP 1 LAST COMMENT_BODY TRUE
J 0
(-3420 5805);
DISPLAY 0.872340 (-3420 5805);
PAINT GREEN (-3420 5805);
DISPLAY INVISIBLE (-3420 5805);
FORCEPROP 1 LAST OFFPAGE TRUE
J 0
(-3050 5775);
DISPLAY 0.872340 (-3050 5775);
PAINT GREEN (-3050 5775);
DISPLAY INVISIBLE (-3050 5775);
FORCEADD QUANTA_TITLE_BLOCK_C..1
(0 0);
FORCEPROP 0 LAST CDS_CON_LAST_MODIFIED Fri Mar 11 14:53:42 2022
J 0
(-1885 15);
DISPLAY INVISIBLE (-1885 15);
FORCEPROP 1 LAST CUSTOM_TXT_CDS <CON_LAST_MODIFIED>
J 0
(-1885 15);
DISPLAY 0.978723 (-1885 15);
FORCEPROP 1 LAST CUSTOM_TXT_CDS <NAME_2>
J 0
(-3175 50);
FORCEPROP 1 LAST CUSTOM_TXT_CDS <NAME_1>
J 0
(-3175 175);
FORCEPROP 1 LAST CUSTOM_TXT_CDS <Q_NUMBER>
J 0
(-1403 103);
DISPLAY 1.212766 (-1403 103);
FORCEPROP 1 LAST CUSTOM_TXT_CDS <Q_PROJ>
J 0
(-2382 102);
DISPLAY 1.212766 (-2382 102);
FORCEPROP 1 LAST CUSTOM_TXT_CDS <Q_REV>
J 0
(-184 103);
DISPLAY 1.212766 (-184 103);
FORCEPROP 1 LAST CUSTOM_TXT_CDS <CON_PAGE_NUM> OF <CON_TOTAL_PAGES>
J 0
(-446 18);
DISPLAY 0.978723 (-446 18);
FORCEPROP 1 LAST Q_TITLE AC CAPS CPU0 G3 TX
J 0
(-9366 26);
DISPLAY 2.446809 (-9366 26);
PAINT GREEN (-9366 26);
FORCEPROP 1 LAST Q_DEPT BU9
J 1
(-3763 49);
DISPLAY 1.957447 (-3763 49);
PAINT GREEN (-3763 49);
FORCEPROP 2 LAST CDS_LIB pure_quanta
J 0
(0 0);
DISPLAY INVISIBLE (0 0);
FORCEPROP 1 LAST COMMENT_BODY TRUE
J 0
(12 -13);
DISPLAY 0.978723 (12 -13);
PAINT GREEN (12 -13);
DISPLAY INVISIBLE (12 -13);
FORCEPROP 1 LAST CDS_LMAN_SYM_OUTLINE -9475,6775,100,-125
J 0
(0 0);
DISPLAY 0.468085 (0 0);
PAINT GREEN (0 0);
DISPLAY INVISIBLE (0 0);
WIRE 17 -1 (-6425 4200)(-6425 4300);
WIRE 17 -1 (-6425 4300)(-6425 4400);
WIRE 17 -1 (-6425 4400)(-6425 4500);
WIRE 17 -1 (-6425 4500)(-6425 4600);
WIRE 17 -1 (-6425 4600)(-6425 4700);
WIRE 17 -1 (-6425 4700)(-6425 4800);
WIRE 17 -1 (-6425 4800)(-6425 4900);
WIRE 17 -1 (-6425 4900)(-6425 5000);
WIRE 17 -1 (-6425 5000)(-6425 5100);
WIRE 17 -1 (-6425 5100)(-6425 5200);
WIRE 17 -1 (-6425 5200)(-6425 5300);
WIRE 17 -1 (-6425 5300)(-6425 5400);
WIRE 17 -1 (-6425 5400)(-6425 5500);
WIRE 17 -1 (-6425 5500)(-6425 5600);
WIRE 17 -1 (-6425 5600)(-6425 5700);
WIRE 17 -1 (-6425 5700)(-6425 5900);
WIRE 17 -1 (-6425 5900)(-7275 5900);
FORCEPROP 2 LAST SIG_NAME P5E_CPU0_G3_TX_DN<15:0>
J 0
(-7160 5910);
DISPLAY 0.680851 (-7160 5910);
WIRE 17 -1 (-6275 5350)(-6275 5450);
WIRE 17 -1 (-6275 5250)(-6275 5350);
WIRE 17 -1 (-6275 5450)(-6275 5550);
WIRE 17 -1 (-6275 5550)(-6275 5650);
WIRE 17 -1 (-6275 5150)(-6275 5250);
WIRE 17 -1 (-6275 5050)(-6275 5150);
WIRE 17 -1 (-6275 5650)(-6275 5750);
WIRE 17 -1 (-6275 5750)(-6275 5950);
WIRE 17 -1 (-6275 4950)(-6275 5050);
WIRE 17 -1 (-6275 4850)(-6275 4950);
WIRE 17 -1 (-6275 5950)(-7275 5950);
FORCEPROP 0 LAST SIG_NAME P5E_CPU0_G3_TX_DP<15:0>
J 0
(-7160 5960);
DISPLAY 0.680851 (-7160 5960);
WIRE 17 -1 (-6275 4750)(-6275 4850);
WIRE 17 -1 (-6275 4650)(-6275 4750);
WIRE 17 -1 (-6275 4550)(-6275 4650);
WIRE 17 -1 (-6275 4450)(-6275 4550);
WIRE 17 -1 (-6275 4350)(-6275 4450);
WIRE 17 -1 (-6275 4250)(-6275 4350);
WIRE 17 -1 (-4450 5650)(-4450 5550);
WIRE 17 -1 (-4450 5750)(-4450 5650);
WIRE 17 -1 (-4450 5550)(-4450 5450);
WIRE 17 -1 (-4450 5450)(-4450 5350);
WIRE 17 -1 (-4450 5950)(-4450 5750);
WIRE 17 -1 (-4450 5950)(-3425 5950);
FORCEPROP 0 LAST SIG_NAME P5E_CPU0_G3_TX_C_DP<15:0>
J 0
(-4310 5960);
DISPLAY 0.680851 (-4310 5960);
WIRE 17 -1 (-4450 5350)(-4450 5250);
WIRE 17 -1 (-4450 5250)(-4450 5150);
WIRE 17 -1 (-4450 5150)(-4450 5050);
WIRE 17 -1 (-4450 5050)(-4450 4950);
WIRE 17 -1 (-4300 5900)(-4300 5700);
FORCEPROP 2 LAST SIG_NAME P5E_CPU0_G3_TX_C_DN<15:0>
J 0
(-4310 5910);
DISPLAY 0.680851 (-4310 5910);
WIRE 17 -1 (-4300 5600)(-4300 5500);
WIRE 17 -1 (-4300 5700)(-4300 5600);
WIRE 17 -1 (-4300 5500)(-4300 5400);
WIRE 17 -1 (-4300 5400)(-4300 5300);
WIRE 17 -1 (-4300 5300)(-4300 5200);
WIRE 17 -1 (-4300 4700)(-4300 4600);
WIRE 17 -1 (-4300 4800)(-4300 4700);
WIRE 17 -1 (-4300 4600)(-4300 4500);
WIRE 17 -1 (-4300 4500)(-4300 4400);
WIRE 17 -1 (-4300 4900)(-4300 4800);
WIRE 17 -1 (-4300 5000)(-4300 4900);
WIRE 17 -1 (-4300 4400)(-4300 4300);
WIRE 17 -1 (-4300 4300)(-4300 4200);
WIRE 17 -1 (-4300 5100)(-4300 5000);
WIRE 17 -1 (-4300 5200)(-4300 5100);
WIRE 17 -1 (-4450 4650)(-4450 4550);
WIRE 17 -1 (-4450 4750)(-4450 4650);
WIRE 17 -1 (-4450 4550)(-4450 4450);
WIRE 17 -1 (-4450 4450)(-4450 4350);
WIRE 17 -1 (-4450 4850)(-4450 4750);
WIRE 17 -1 (-4450 4950)(-4450 4850);
WIRE 17 -1 (-4450 4350)(-4450 4250);
WIRE 17 -1 (-4300 5900)(-3425 5900);
WIRE 16 -1 (-5575 4275)(-6325 4275);
WIRE 16 -1 (-5575 4325)(-6175 4325);
WIRE 16 -1 (-5575 4475)(-6325 4475);
WIRE 16 -1 (-5575 4425)(-6175 4425);
WIRE 16 -1 (-4550 4625)(-5425 4625);
WIRE 16 -1 (-4400 4675)(-5425 4675);
WIRE 16 -1 (-4550 4725)(-5425 4725);
WIRE 16 -1 (-4400 4775)(-5425 4775);
WIRE 16 -1 (-4550 4825)(-5425 4825);
WIRE 16 -1 (-4400 4875)(-5425 4875);
WIRE 16 -1 (-4550 4925)(-5425 4925);
WIRE 16 -1 (-4400 4975)(-5425 4975);
WIRE 16 -1 (-4550 5025)(-5425 5025);
WIRE 16 -1 (-4400 5075)(-5425 5075);
WIRE 16 -1 (-4550 5125)(-5425 5125);
WIRE 16 -1 (-4400 5175)(-5425 5175);
WIRE 16 -1 (-4550 5225)(-5425 5225);
WIRE 16 -1 (-4400 5275)(-5425 5275);
WIRE 16 -1 (-4550 5325)(-5425 5325);
WIRE 16 -1 (-4400 5375)(-5425 5375);
WIRE 16 -1 (-5575 5575)(-6325 5575);
WIRE 16 -1 (-4400 4175)(-5425 4175);
WIRE 16 -1 (-4550 4225)(-5425 4225);
WIRE 16 -1 (-5575 4225)(-6175 4225);
WIRE 16 -1 (-4400 4275)(-5425 4275);
WIRE 16 -1 (-4550 4325)(-5425 4325);
WIRE 16 -1 (-4400 4375)(-5425 4375);
WIRE 16 -1 (-4550 4425)(-5425 4425);
WIRE 16 -1 (-4400 4475)(-5425 4475);
WIRE 16 -1 (-4550 4525)(-5425 4525);
WIRE 16 -1 (-5575 4375)(-6325 4375);
WIRE 16 -1 (-4400 4575)(-5425 4575);
WIRE 16 -1 (-5575 4575)(-6325 4575);
WIRE 16 -1 (-5575 4875)(-6325 4875);
WIRE 16 -1 (-5575 4525)(-6175 4525);
WIRE 16 -1 (-5575 4625)(-6175 4625);
WIRE 16 -1 (-5575 5225)(-6175 5225);
WIRE 16 -1 (-5575 5275)(-6325 5275);
WIRE 16 -1 (-5575 5375)(-6325 5375);
WIRE 16 -1 (-5575 4725)(-6175 4725);
WIRE 16 -1 (-5575 5125)(-6175 5125);
WIRE 16 -1 (-5575 4675)(-6325 4675);
WIRE 16 -1 (-4400 5475)(-5425 5475);
WIRE 16 -1 (-4400 5575)(-5425 5575);
WIRE 16 -1 (-4400 5675)(-5425 5675);
WIRE 16 -1 (-4550 5725)(-5425 5725);
WIRE 16 -1 (-4550 5625)(-5425 5625);
WIRE 16 -1 (-4550 5425)(-5425 5425);
WIRE 16 -1 (-5575 4775)(-6325 4775);
WIRE 16 -1 (-5575 4925)(-6175 4925);
WIRE 16 -1 (-5575 4975)(-6325 4975);
WIRE 16 -1 (-5575 5025)(-6175 5025);
WIRE 16 -1 (-4550 5525)(-5425 5525);
WIRE 16 -1 (-5575 5625)(-6175 5625);
WIRE 16 -1 (-5575 5475)(-6325 5475);
WIRE 16 -1 (-5575 4825)(-6175 4825);
WIRE 16 -1 (-5575 5325)(-6175 5325);
WIRE 16 -1 (-5575 5525)(-6175 5525);
WIRE 16 -1 (-5575 5075)(-6325 5075);
WIRE 16 -1 (-5575 5175)(-6325 5175);
WIRE 16 -1 (-6325 5675)(-5575 5675);
WIRE 16 -1 (-6175 5725)(-5575 5725);
WIRE 16 -1 (-5575 5425)(-6175 5425);
WIRE 16 -1 (-5575 4175)(-6325 4175);
FORCENOTE
CPU0 G3[15:0] TO OCP SLOT#0
(-3575 5025) 0;
DISPLAY LEFT (-3575 5025);
DISPLAY 2.000000 (-3575 5025);
QUIT
